G04 ================== begin FILE IDENTIFICATION RECORD ==================*
G04 Layout Name:  9054_F0T_PDB_BD_GPU_F_V04_1213_1550.brd*
G04 Film Name:    in1*
G04 File Format:  Gerber RS274X*
G04 File Origin:  Cadence Allegro 17.2-S081*
G04 Origin Date:  Wed Dec 28 10:19:02 2022*
G04 *
G04 Layer:  DRAWING FORMAT/TITLE_BLOCK_A*
G04 Layer:  PIN/SPECIAL_DRILL*
G04 Layer:  DRAWING FORMAT/TITLE_BLOCK*
G04 Layer:  VIA CLASS/IN1*
G04 Layer:  PIN/IN1*
G04 Layer:  MANUFACTURING/PHOTOPLOT_OUTLINE*
G04 Layer:  ETCH/IN1*
G04 Layer:  DRAWING FORMAT/TITLE_DATA_IN1*
G04 *
G04 Offset:    (0.00 0.00)*
G04 Mirror:    No*
G04 Mode:      Positive*
G04 Rotation:  0*
G04 FullContactRelief:  No*
G04 UndefLineWidth:     6.00*
G04 ================== end FILE IDENTIFICATION RECORD ====================*
%FSLAX25Y25*MOIN*%
%IR0*IPPOS*OFA0.00000B0.00000*MIA0B0*SFA1.00000B1.00000*%
%ADD20O,.123X.074*%
%ADD10C,.02*%
%ADD13C,.03*%
%ADD21C,.061*%
%ADD15C,.07*%
%ADD18C,.066*%
%ADD17C,.06015*%
%ADD16C,.085*%
%ADD14C,.04552*%
%ADD11C,.4*%
%ADD19C,.414*%
%ADD22C,.01*%
%ADD23C,.015*%
%ADD24C,.025*%
%ADD25C,.018*%
%ADD26C,.006*%
%ADD27C,.0051*%
%ADD30C,.03004*%
%ADD31C,.07004*%
%ADD33C,.08004*%
%ADD32C,.12004*%
%ADD37C,.12606*%
%ADD35C,.11706*%
%ADD34O,.40438X.60123*%
%ADD29C,.16506*%
%ADD36C,.28606*%
%ADD28C,.19806*%
G75*
%LPD*%
G75*
G36*
G01X1437008Y673787D02*
X1590551D01*
G02X1608236Y656102I0J-17685D01*
G01Y642913D01*
G03X1629921Y621228I21685J0D01*
G01X1712598D01*
G02X1730283Y603543I0J-17685D01*
G01Y538465D01*
G03X1751968Y516780I21685J0D01*
G01X1854331D01*
G02X1872016Y499095I0J-17685D01*
G01Y85709D01*
G02X1854331Y68024I-17685J0D01*
G01X1751968D01*
G03X1730283Y46339I1J-21686D01*
G01Y19685D01*
G02X1712598Y2000I-17685J0D01*
G01X19685D01*
G02X2000Y19685I0J17685D01*
G01Y603543D01*
G02X19685Y621228I17685J0D01*
G01X102362D01*
G03X124047Y642913I0J21685D01*
G01Y656102D01*
G02X141732Y673787I17685J0D01*
G01X295276D01*
G02X312961Y656102I0J-17685D01*
G01Y635039D01*
G03X326772Y621228I13811J0D01*
G01X328740D01*
G02X346425Y603543I0J-17685D01*
G01Y435039D01*
G03X377952Y403512I31528J1D01*
G01X1354331D01*
G03X1385858Y435039I0J31527D01*
G01Y603543D01*
G02X1403543Y621228I17685J0D01*
G01X1405512D01*
G03X1419323Y635039I0J13811D01*
G01Y656102D01*
G02X1437008Y673787I17685J0D01*
G37*
%LPC*%
G75*
G36*
G01X1421322Y656102D02*
G02X1437008Y671788I15686J0D01*
G01X1590551D01*
G02X1606237Y656102I0J-15686D01*
G01Y642913D01*
G03X1629921Y619229I23684J0D01*
G01X1712598D01*
G02X1728284Y603543I0J-15686D01*
G01Y538465D01*
G03X1751968Y514781I23685J0D01*
G01X1854331D01*
G02X1870017Y499095I0J-15686D01*
G01Y85709D01*
G02X1854331Y70023I-15686J0D01*
G01X1751968D01*
G03X1728284Y46339I1J-23685D01*
G01Y19685D01*
G02X1712598Y3999I-15686J0D01*
G01X19685D01*
G02X3999Y19685I0J15686D01*
G01Y603543D01*
G02X19685Y619229I15686J0D01*
G01X102362D01*
G03X126046Y642913I0J23684D01*
G01Y656102D01*
G02X141732Y671788I15686J0D01*
G01X295276D01*
G02X303031Y669737I0J-15687D01*
G01X191750D01*
G02X191608Y669678I-142J141D01*
G01X154866D01*
G03X154724Y669619I0J-200D01*
G01X152891Y667786D01*
G03X152832Y667644I141J-142D01*
G01Y599674D01*
G03X152891Y599532I200J0D01*
G01X154661Y597762D01*
G03X154803Y597703I142J141D01*
G01X180582D01*
G03X180724Y597762I0J200D01*
G01X182057Y599095D01*
G03X182116Y599237I-141J142D01*
G01Y637479D01*
G02X182175Y637621I200J0D01*
G01X189925Y645371D01*
G02X190067Y645430I142J-141D01*
G01X304135D01*
G03X304277Y645489I0J200D01*
G01X305670Y646882D01*
G03X305729Y647024I-141J142D01*
G01Y667798D01*
G02X310962Y656102I-10454J-11696D01*
G01Y635039D01*
G03X326772Y619229I15810J0D01*
G01X328740D01*
G02X344426Y603543I0J-15686D01*
G01Y435039D01*
G03X377952Y401513I33527J1D01*
G01X1354331D01*
G03X1387857Y435039I0J33526D01*
G01Y603543D01*
G02X1403543Y619229I15686J0D01*
G01X1405512D01*
G03X1421322Y635039I0J15810D01*
G01Y656102D01*
G37*
G54D35*
X263780Y659961D03*
%LPD*%
G75*
G36*
G01X10467Y611952D02*
X116541D01*
G02X116683Y611893I0J-200D01*
G01X122107Y606469D01*
G02X122166Y606327I-141J-142D01*
G01Y154352D01*
G03X122225Y154210I200J0D01*
G01X161905Y114530D01*
G03X162047Y114471I142J141D01*
G01X162325D01*
G02X162467Y114412I0J-200D01*
G01X175362Y101517D01*
X175377Y101476D01*
G03X175439Y101334I1406J529D01*
G01X175462Y101287D01*
X175457Y101184D01*
X175250Y100851D01*
G02X175080Y100756I-170J105D01*
G01X159173D01*
G02X159032Y100815I1J200D01*
G01X158277Y101570D01*
X158250Y101617D01*
X158243Y101644D01*
G03X156785Y102787I-1458J-358D01*
G03X155283Y101285I0J-1502D01*
G03X156426Y99827I1501J0D01*
G01X156453Y99820D01*
X156500Y99793D01*
X157642Y98652D01*
G03X157751Y98554I893J884D01*
G01X157794Y98520D01*
G03X158426Y98258I779J986D01*
G01X158477Y98252D01*
G03X158624Y98244I142J1248D01*
G01X180600D01*
G03X181488Y98612I0J1255D01*
G01X182773Y99896D01*
G02X182915Y99955I142J-141D01*
G01X289648D01*
G02X289790Y99896I0J-200D01*
G01X309438Y80249D01*
G03X310326Y79880I889J887D01*
G01X338541D01*
G02X338682Y79822I0J-200D01*
G01X338845Y79659D01*
G02X338889Y79441I-141J-142D01*
G01X338865Y79384D01*
X338765Y79318D01*
X329481D01*
G03X328593Y78949I1J-1256D01*
G01X325554Y75911D01*
X325510Y75896D01*
G03X324638Y75108I491J-1419D01*
G01X324617Y75064D01*
X324540Y75004D01*
X324168Y74938D01*
G02X323992Y74994I-34J197D01*
G01X323622Y75363D01*
G03X322734Y75732I-889J-887D01*
G01X322353D01*
X322301Y75746D01*
X322277Y75760D01*
G03X321500Y75977I-778J-1285D01*
G03Y72973I0J-1502D01*
G03X322133Y73113I0J1501D01*
G01X322191Y73140D01*
X322314Y73118D01*
X324923Y70509D01*
G02X324967Y70291I-141J-142D01*
G01X324943Y70234D01*
X324844Y70168D01*
X322693D01*
G02X322552Y70226I0J200D01*
G01X318526Y74252D01*
X318496Y74332D01*
X318499Y74376D01*
G03X318502Y74475I-1499J95D01*
G03X315498I-1502J0D01*
G03X315821Y73544I1503J0D01*
G02X315848Y73500I-156J-126D01*
G03X316112Y73113I1152J502D01*
G01X320808Y68416D01*
G02X320865Y68250I-141J-141D01*
G01X320820Y67890D01*
X320770Y67814D01*
X320730Y67790D01*
G03X320723Y67785I867J-1221D01*
G02X320619Y67756I-104J171D01*
G01X316001D01*
G03X315113Y67388I0J-1255D01*
G01X313612Y65887D01*
G03X313244Y64999I887J-888D01*
G01Y59603D01*
G02X313185Y59462I-200J1D01*
G01X295712Y41989D01*
G02X295570Y41930I-142J141D01*
G01X291902D01*
G03X291760Y41871I0J-200D01*
G01X268051Y18162D01*
G03X267992Y18020I141J-142D01*
G01Y10171D01*
G02X267933Y10029I-200J0D01*
G01X265995Y8091D01*
G02X265746Y8065I-141J142D01*
G01X265357Y8315D01*
X265313Y8448D01*
X265338Y8515D01*
G03X265644Y10197I-4472J1682D01*
G03X256088I-4778J0D01*
G03X257994Y6379I4777J0D01*
G01X258046Y6340D01*
X258084Y6217D01*
X257943Y5796D01*
G02X257753Y5659I-190J63D01*
G01X253979D01*
G02X253789Y5796I0J200D01*
G01X253648Y6217D01*
X253686Y6340D01*
X253738Y6379D01*
G03X255644Y10197I-2871J3818D01*
G03X250866Y14975I-4778J0D01*
G03X248168Y14140I0J-4778D01*
G01X248119Y14107D01*
X248000Y14104D01*
X247588Y14362D01*
X247538Y14470D01*
X247547Y14529D01*
G03X245418Y10525I-6680J984D01*
G01X245463Y10565D01*
X245580Y10584D01*
X246024Y10387D01*
X246088Y10287D01*
Y10227D01*
Y10197D01*
G03X247994Y6379I4777J0D01*
G01X248046Y6340D01*
X248084Y6217D01*
X247943Y5796D01*
G02X247753Y5659I-190J63D01*
G01X16081D01*
G02X15939Y5718I0J200D01*
G01X6736Y14921D01*
G02X6677Y15063I141J142D01*
G01Y608162D01*
G02X6736Y608304I200J0D01*
G01X10325Y611893D01*
G02X10467Y611952I142J-141D01*
G37*
G36*
G01X135666Y667500D02*
X147177D01*
G02X147319Y667441I0J-200D01*
G01X148145Y666615D01*
G02X148204Y666473I-141J-142D01*
G01Y595359D01*
G03X148263Y595217I200J0D01*
G01X150383Y593097D01*
G03X150525Y593038I142J141D01*
G01X185999D01*
G03X186141Y593097I0J200D01*
G01X187912Y594868D01*
G03X187971Y595010I-141J142D01*
G01Y633887D01*
G02X188030Y634029I200J0D01*
G01X190442Y636441D01*
G02X190584Y636500I142J-141D01*
G01X202619D01*
G02X202795Y636394I-1J-200D01*
G03X212953I5079J2700D01*
G02X213129Y636500I177J-94D01*
G01X305415D01*
G02X305557Y636441I0J-200D01*
G01X306362Y635636D01*
G02X306421Y635494I-141J-142D01*
G01Y610035D01*
G02X306362Y609893I-200J0D01*
G01X288191Y591722D01*
G03X288132Y591580I141J-142D01*
G01Y547617D01*
G03X288191Y547475I200J0D01*
G01X300855Y534811D01*
G03X300997Y534752I142J141D01*
G01X329383D01*
G02X329525Y534693I0J-200D01*
G01X334941Y529277D01*
G02X335000Y529135I-141J-142D01*
G01Y418083D01*
G03X335059Y417941I200J0D01*
G01X358941Y394059D01*
G03X359083Y394000I142J141D01*
G01X432567D01*
G02X432709Y393941I0J-200D01*
G01X441793Y384857D01*
G02X441852Y384715I-141J-142D01*
G01Y340424D01*
G03X441911Y340282I200J0D01*
G01X454984Y327209D01*
G03X455126Y327150I142J141D01*
G01X466934D01*
X468338Y325746D01*
Y212032D01*
X440585D01*
G03X441602Y214500I-2486J2468D01*
G03X434598I-3502J0D01*
G03X435615Y212032I3503J0D01*
G01X434050D01*
G03X430608Y214891I-3442J-642D01*
G03X427106Y211389I0J-3502D01*
G03X430573Y207887I3502J0D01*
G01X431430Y207030D01*
X468338D01*
Y167393D01*
X440438D01*
G03X441602Y170000I-2337J2607D01*
G03X434598I-3502J0D01*
G03X435762Y167393I3501J0D01*
G01X431763D01*
G03X428277Y170558I-3486J-337D01*
G03X424775Y167056I0J-3502D01*
G03X428242Y163554I3502J0D01*
G01X429405Y162391D01*
X468338D01*
Y53486D01*
X467254Y52402D01*
X399396D01*
X356331Y95467D01*
G03X356189Y95526I-142J-141D01*
G01X322520D01*
G02X322378Y95585I0J200D01*
G01X283963Y134000D01*
X158583D01*
X134083Y158500D01*
G02X134024Y158642I141J142D01*
G01Y587858D01*
G02X134083Y588000I200J0D01*
G01Y665917D01*
G02X134142Y666059I200J0D01*
G01X135524Y667441D01*
G02X135666Y667500I142J-141D01*
G37*
G36*
G01X822797Y338214D02*
X902917D01*
G02X903059Y338155I0J-200D01*
G01X942262D01*
G02X942404Y338096I0J-200D01*
G01X974941Y305559D01*
G03X975083Y305500I142J141D01*
G01X1012417D01*
G02X1012559Y305441I0J-200D01*
G01X1030441Y287559D01*
G02X1030500Y287417I-141J-142D01*
G01Y285583D01*
G02X1030441Y285441I-200J0D01*
G01X1030266Y285266D01*
X1030173Y285237D01*
X1030124Y285246D01*
G03X1029500Y285302I-624J-3446D01*
G03Y278298I0J-3502D01*
G03X1030787Y278543I0J3503D01*
G01X1030843Y278565D01*
X1030959Y278541D01*
X1033041Y276459D01*
G02X1033100Y276317I-141J-142D01*
G01Y257402D01*
G02X1032979Y257218I-200J0D01*
G03X1030858Y254000I1381J-3218D01*
G03X1034360Y250498I3502J0D01*
G03X1037335Y252153I0J3501D01*
G01X1037360Y252192D01*
X1037436Y252240D01*
X1037793Y252282D01*
G02X1037958Y252224I23J-199D01*
G01X1044895Y245287D01*
G02X1044954Y245145I-141J-142D01*
G01Y213997D01*
G02X1044895Y213855I-200J0D01*
G01X1036719Y205679D01*
G02X1036577Y205620I-142J141D01*
G01X1024386D01*
G02X1024244Y205679I0J200D01*
G01X1018050Y211873D01*
G03X1017908Y211932I-142J-141D01*
G01X904921D01*
G03X904779Y211873I0J-200D01*
G01X899366Y206460D01*
G03X899307Y206318I141J-142D01*
G01Y124183D01*
G03X899366Y124041I200J0D01*
G01Y115287D01*
G03X899425Y115145I200J0D01*
G01X905585Y108985D01*
G03X905727Y108926I142J141D01*
G01X1089803D01*
G02X1089945Y108867I0J-200D01*
G01X1091725Y107087D01*
G02X1091784Y106945I-141J-142D01*
G01Y59623D01*
G03X1091843Y59481I200J0D01*
G01X1104109Y47215D01*
G03X1104251Y47156I142J141D01*
G01X1356517D01*
G02X1356659Y47097I0J-200D01*
G01X1359841Y43915D01*
G02X1359900Y43773I-141J-142D01*
G01Y31083D01*
G02X1359841Y30941I-200J0D01*
G01X1357705Y28805D01*
G02X1357564Y28746I-142J141D01*
G01X879769D01*
G02X879628Y28805I1J200D01*
G01X871992Y36441D01*
G03X871850Y36500I-142J-141D01*
G01X863641D01*
G03X863499Y36441I0J-200D01*
G01X851655Y24597D01*
G02X851513Y24538I-142J141D01*
G01X479045D01*
G02X478903Y24597I0J200D01*
G01X476059Y27441D01*
G02X476000Y27583I141J142D01*
G01Y45978D01*
G02X476059Y46120I200J0D01*
G01X477441Y47502D01*
G02X477583Y47561I142J-141D01*
G01X632300D01*
G03X632442Y47620I0J200D01*
G01X640441Y55619D01*
G03X640500Y55761I-141J142D01*
G01Y106015D01*
G02X640559Y106157I200J0D01*
G01X643899Y109497D01*
G02X644041Y109556I142J-141D01*
G01X827231D01*
G03X827373Y109615I0J200D01*
G01X834076Y116318D01*
G03X834135Y116460I-141J142D01*
G01Y123643D01*
G02X834194Y123785I200J0D01*
G01Y206383D01*
G03X834135Y206525I-200J0D01*
G01X829524Y211136D01*
G03X829382Y211195I-142J-141D01*
G01X721252D01*
G03X721110Y211136I0J-200D01*
G01X709040Y199066D01*
G03X708981Y198924I141J-142D01*
G01Y194942D01*
G02X708922Y194800I-200J0D01*
G01X708109Y193987D01*
G02X707967Y193928I-142J141D01*
G01X702377D01*
G02X702235Y193987I0J200D01*
G01X701253Y194969D01*
G02X701194Y195111I141J142D01*
G01Y195624D01*
G02X701278Y195787I200J0D01*
G01X701585Y196004D01*
X701680Y196018D01*
X701726Y196002D01*
G03X702223Y195917I498J1417D01*
G03Y198921I0J1502D01*
G03X701726Y198836I1J-1502D01*
G01X701680Y198820D01*
X701585Y198834D01*
X701278Y199051D01*
G02X701194Y199214I116J163D01*
G01Y201844D01*
G02X701253Y201986I200J0D01*
G01X704315Y205048D01*
X704373Y205077D01*
X704405Y205081D01*
G03X705688Y206364I-205J1488D01*
G01X705692Y206396D01*
X705721Y206454D01*
X714041Y214774D01*
G03X714100Y214916I-141J142D01*
G01Y270772D01*
G02X714228Y270958I200J-1D01*
G01X714633Y271115D01*
X714754Y271087D01*
X714796Y271041D01*
G03X717384Y269898I2588J2358D01*
G03X720886Y273400I0J3502D01*
G03X720441Y275108I-3502J0D01*
G01X720419Y275147D01*
X720413Y275234D01*
X720552Y275604D01*
X720614Y275665D01*
X720656Y275680D01*
G03X722986Y278980I-1172J3300D01*
G03X715982I-3502J0D01*
G03X716427Y277272I3502J0D01*
G01X716449Y277233D01*
X716455Y277146D01*
X716316Y276776D01*
X716254Y276715D01*
X716212Y276700D01*
G03X714796Y275759I1172J-3300D01*
G01X714754Y275713D01*
X714633Y275685D01*
X714228Y275842D01*
G02X714100Y276028I72J187D01*
G01Y296417D01*
G02X714159Y296559I200J0D01*
G01X715541Y297941D01*
G02X715683Y298000I142J-141D01*
G01X722852D01*
G03X722925Y297998I78J1500D01*
G03X722998Y298000I-5J1502D01*
G01X726417D01*
G03X726559Y298059I0J200D01*
G01X732185Y303685D01*
G02X732326Y303744I142J-141D01*
G01X786400D01*
G03X787288Y304112I0J1255D01*
G01X787618Y304441D01*
G02X787760Y304500I142J-141D01*
G01X788917D01*
G03X789059Y304559I0J200D01*
G01X822655Y338155D01*
G02X822797Y338214I142J-141D01*
G37*
G36*
G01X487384Y181700D02*
X535484D01*
X558800D01*
X560000Y180500D01*
X560500D01*
Y165700D01*
X554300Y159500D01*
X547000D01*
X541500Y154000D01*
Y131400D01*
X543000Y129900D01*
X558019D01*
X558984Y128935D01*
Y52893D01*
X556891Y50800D01*
X487584D01*
X486284Y52100D01*
Y180600D01*
X487384Y181700D01*
G37*
G36*
G01X519884Y314900D02*
X487384D01*
X486284Y313800D01*
Y185300D01*
X487584Y184000D01*
X519784D01*
X559784D01*
X560449Y184665D01*
Y226813D01*
X536884Y250378D01*
Y267900D01*
Y313500D01*
X535484Y314900D01*
X529784D01*
X519884D01*
G37*
G36*
G01X581007Y262968D02*
X584355D01*
X585328Y261995D01*
Y238544D01*
X608026Y215846D01*
X658462D01*
X658544Y215928D01*
X690487D01*
X692003Y214412D01*
Y211285D01*
X684133Y203415D01*
X678547D01*
X675872Y200740D01*
Y170609D01*
X683819Y162662D01*
X755950D01*
X779288Y186000D01*
X825201D01*
G02X825343Y185941I0J-200D01*
G01X826725Y184559D01*
G02X826784Y184417I-141J-142D01*
G01Y119746D01*
X826754Y119716D01*
Y119337D01*
G02X826695Y119195I-200J0D01*
G01X822545Y115045D01*
X637425D01*
X630919Y108539D01*
Y60576D01*
X620761Y50418D01*
X568502D01*
X567116Y51804D01*
Y113101D01*
X569140Y115125D01*
Y127980D01*
X569908Y128748D01*
X580500D01*
X582000Y130248D01*
Y154500D01*
X579500Y157000D01*
X574200D01*
X565500Y165700D01*
Y184500D01*
X565554Y184554D01*
Y184593D01*
Y244752D01*
X569294Y248492D01*
Y251255D01*
X581007Y262968D01*
G37*
G36*
G01X720246Y200520D02*
X758811D01*
X760285Y199046D01*
Y183828D01*
X746957Y170500D01*
X732780D01*
X719273Y184007D01*
Y199547D01*
X720246Y200520D01*
G37*
G36*
G01X1175654Y262968D02*
X1185334D01*
X1186969Y261333D01*
X1193926D01*
X1195168Y260091D01*
Y173668D01*
X1183000Y161500D01*
X1175716Y154216D01*
Y131155D01*
X1177103Y129768D01*
X1185374D01*
X1186647Y128495D01*
X1193881D01*
X1195168Y127208D01*
Y51178D01*
X1194408Y50418D01*
X1113993D01*
X1100334Y64077D01*
Y105768D01*
X1091057Y115045D01*
X907614D01*
G02X907472Y115104I0J200D01*
G01X905559Y117017D01*
G02X905500Y117159I141J142D01*
G01Y184417D01*
G02X905559Y184559I200J0D01*
G01X906941Y185941D01*
G02X907083Y186000I142J-141D01*
G01X956100D01*
X979438Y162662D01*
X1007900D01*
X1018738Y173500D01*
X1056700D01*
X1112150Y228950D01*
X1156150D01*
X1169784Y242584D01*
Y257098D01*
X1175654Y262968D01*
G37*
G36*
G01X974461Y200520D02*
X1013026D01*
X1014500Y199046D01*
Y183828D01*
X1001172Y170500D01*
X986995D01*
X973488Y184007D01*
Y199547D01*
X974461Y200520D01*
G37*
G36*
G01X1226800Y181700D02*
X1274900D01*
X1276000Y180600D01*
Y52100D01*
X1274700Y50800D01*
X1203809D01*
X1203300Y51309D01*
Y113709D01*
X1205048Y115457D01*
Y128520D01*
X1206428Y129900D01*
X1220600D01*
X1225400Y134700D01*
Y180300D01*
X1226800Y181700D01*
G37*
G36*
G01Y314900D02*
X1274900D01*
X1276000Y313800D01*
Y185300D01*
X1274700Y184000D01*
X1203832D01*
X1203300Y184532D01*
Y245793D01*
X1204741Y247234D01*
Y262052D01*
X1205789Y263100D01*
X1220600D01*
X1225400Y267900D01*
Y313500D01*
X1226800Y314900D01*
G37*
G36*
G01X1294253Y314153D02*
X1313285D01*
X1324287Y303151D01*
X1399267D01*
X1467083Y235336D01*
X1567834D01*
X1601553Y201617D01*
G02X1601612Y201475I-141J-142D01*
G01Y180651D01*
X1601597Y180599D01*
X1601583Y180575D01*
G03X1601553Y180470I170J-105D01*
G01Y170136D01*
G02X1601494Y169994I-200J0D01*
G01X1594559Y163059D01*
G03X1594500Y162917I141J-142D01*
G01Y154956D01*
G02X1594441Y154814I-200J0D01*
G01X1594162Y154535D01*
G02X1594020Y154476I-142J141D01*
G01X1589548D01*
G03X1589406Y154417I0J-200D01*
G01X1587050Y152061D01*
G03X1586991Y151919I141J-142D01*
G01Y128728D01*
G02X1586932Y128586I-200J0D01*
G01X1586358Y128012D01*
G02X1586216Y127953I-142J141D01*
G01X1545144D01*
G02X1545002Y128012I0J200D01*
G01X1543897Y129117D01*
G03X1543755Y129176I-142J-141D01*
G01X1446818D01*
G03X1446676Y129117I0J-200D01*
G01X1399801Y82242D01*
G02X1399789Y82231I-141J142D01*
G01X1395058Y77500D01*
X1294024D01*
X1293600Y77924D01*
Y144141D01*
X1331689D01*
G03X1334140Y143140I2451J2500D01*
G03Y150144I0J3502D01*
G03X1331689Y149143I0J-3501D01*
G01X1327328D01*
G03X1327602Y150500I-3228J1358D01*
G03X1324100Y154002I-3502J0D01*
G01X1324096D01*
G03X1323526Y153955I2J-3502D01*
G02X1323141Y154590I-66J394D01*
G03X1323848Y156700I-2795J2110D01*
G03X1320346Y153198I-3502J0D01*
G01X1320350D01*
G03X1320920Y153245I-2J3502D01*
G02X1321305Y152610I66J-394D01*
G03X1320598Y150500I2795J-2110D01*
G03X1320872Y149143I3502J1D01*
G01X1293600D01*
Y188143D01*
X1330220D01*
G03X1332671Y187142I2451J2500D01*
G03Y194146I0J3502D01*
G03X1330220Y193145I0J-3501D01*
G01X1327131D01*
G03X1327602Y194898I-3031J1754D01*
G01Y194900D01*
G03X1324100Y198402I-3502J0D01*
G01X1324096D01*
G03X1323526Y198355I2J-3502D01*
G02X1323141Y198990I-66J394D01*
G03X1323848Y201100I-2795J2110D01*
G03X1320346Y197598I-3502J0D01*
G01X1320350D01*
G03X1320920Y197645I-2J3502D01*
G02X1321305Y197010I66J-394D01*
G03X1320598Y194900I2795J-2110D01*
G01Y194898D01*
G03X1321069Y193145I3502J1D01*
G01X1294010D01*
X1293600Y193555D01*
Y313500D01*
X1294253Y314153D01*
G37*
G36*
G01X1564583Y667500D02*
X1577957D01*
X1578031Y667470D01*
X1578059Y667441D01*
X1579441Y666059D01*
G02X1579500Y665917I-141J-142D01*
G01Y588083D01*
G03X1579559Y587941I200J0D01*
G01X1583441Y584059D01*
G03X1583583Y584000I142J141D01*
G01X1629457D01*
X1629531Y583970D01*
X1629559Y583941D01*
X1633882Y579618D01*
G02X1633941Y579476I-141J-142D01*
G01Y538641D01*
G03X1633970Y538538I200J1D01*
G01X1633971Y538537D01*
X1633985Y538513D01*
X1633992Y538488D01*
G02X1634000Y538433I-192J-56D01*
G01Y301340D01*
X1626541Y293881D01*
X1479521D01*
X1399041Y374361D01*
Y424247D01*
G03X1399100Y424389I-141J142D01*
G01Y532041D01*
G02X1399159Y532183I200J0D01*
G01X1401074Y534098D01*
X1429187D01*
X1443496Y548407D01*
Y593169D01*
X1427355Y609310D01*
Y635766D01*
G02X1427414Y635908I200J0D01*
G01X1427947Y636441D01*
G02X1428089Y636500I142J-141D01*
G01X1519154D01*
G02X1519330Y636394I-1J-200D01*
G03X1529488I5079J2700D01*
G02X1529664Y636500I177J-94D01*
G01X1560417D01*
G03X1560559Y636559I0J200D01*
G01X1561941Y637941D01*
G03X1562000Y638083I-141J142D01*
G01Y664957D01*
X1562030Y665031D01*
X1562059Y665059D01*
X1564441Y667441D01*
G02X1564583Y667500I142J-141D01*
G37*
G36*
G01X1429780Y668790D02*
X1542860D01*
G02X1543002Y668731I0J-200D01*
G01X1544458Y667275D01*
G02X1544517Y667133I-141J-142D01*
G01Y646707D01*
G02X1544458Y646565I-200J0D01*
G01X1542749Y644856D01*
G02X1542607Y644797I-142J141D01*
G01X1525166D01*
X1525153Y644799D01*
G03X1523665I-744J-5705D01*
G01X1523652Y644797D01*
X1428543D01*
G02X1428401Y644856I0J200D01*
G01X1426504Y646753D01*
G02X1426445Y646895I141J142D01*
G01Y665455D01*
G02X1426504Y665597I200J0D01*
G01X1429638Y668731D01*
G02X1429780Y668790I142J-141D01*
G37*
G36*
G01X1586413Y667506D02*
X1598275D01*
G02X1598417Y667447I0J-200D01*
G01X1599811Y666053D01*
G02X1599870Y665911I-141J-142D01*
G01Y621683D01*
G03X1599929Y621541I200J0D01*
G01X1604410Y617060D01*
G03X1604552Y617001I142J141D01*
G01X1715403D01*
G02X1715545Y616942I0J-200D01*
G01X1725503Y606984D01*
G02X1725562Y606842I-141J-142D01*
G01Y526278D01*
G03X1725621Y526136I200J0D01*
G01X1742381Y509376D01*
G03X1742523Y509317I142J141D01*
G01X1859232D01*
G02X1859374Y509258I0J-200D01*
G01X1866057Y502575D01*
G02X1866116Y502433I-141J-142D01*
G01Y80631D01*
G02X1866057Y80489I-200J0D01*
G01X1857361Y71793D01*
G02X1857219Y71734I-142J141D01*
G01X1782588D01*
G02X1782446Y71793I0J200D01*
G01X1779588Y74651D01*
G02X1779529Y74793I141J142D01*
G01Y146551D01*
G02X1779588Y146693I200J0D01*
G01X1818941Y186046D01*
G03X1819000Y186188I-141J142D01*
G01Y187927D01*
G03X1819002Y188000I-1500J78D01*
G03X1819000Y188073I-1502J-5D01*
G01Y194221D01*
G03X1818941Y194363I-200J0D01*
G01X1803559Y209745D01*
G03X1803417Y209804I-142J-141D01*
G01X1667279D01*
G02X1667137Y209863I0J200D01*
G01X1640483Y236517D01*
G02X1640424Y236659I141J142D01*
G01Y582156D01*
G03X1640365Y582298I-200J0D01*
G01X1632801Y589862D01*
G03X1632659Y589921I-142J-141D01*
G01X1587359D01*
G02X1587217Y589980I0J200D01*
G01X1584816Y592381D01*
G02X1584757Y592523I141J142D01*
G01Y665850D01*
G02X1584816Y665992I200J0D01*
G01X1586271Y667447D01*
G02X1586413Y667506I142J-141D01*
G37*
G36*
G01X1632780Y149500D02*
X1663917D01*
G02X1664059Y149441I0J-200D01*
G01X1683941Y129559D01*
G02X1684000Y129417I-141J-142D01*
G01Y128599D01*
G02X1683953Y128469I-200J-1D01*
G03X1683598Y127500I1147J-970D01*
G03X1683953Y126531I1502J1D01*
G02X1684000Y126401I-153J-129D01*
G01Y105583D01*
G02X1683941Y105441I-200J0D01*
G01X1670559Y92059D01*
G02X1670417Y92000I-142J141D01*
G01X1612583D01*
G02X1612441Y92059I0J200D01*
G01X1605559Y98941D01*
G02X1605500Y99083I141J142D01*
G01Y146917D01*
G02X1605559Y147059I200J0D01*
G01X1606110Y147610D01*
G02X1606251Y147668I141J-142D01*
G01X1617219D01*
G02X1617323Y147640I2J-200D01*
G03X1618100Y147423I778J1285D01*
G03X1619602Y148925I0J1502D01*
G03X1619596Y149063I-1502J4D01*
G01X1619592Y149105D01*
X1619618Y149185D01*
X1619846Y149435D01*
G02X1619994Y149500I148J-135D01*
G01X1629866D01*
G02X1630066Y149300I0J-200D01*
G01Y116021D01*
G02X1630038Y115917I-200J-2D01*
G03X1629821Y115140I1285J-778D01*
G03X1632825I1502J0D01*
G03X1632608Y115917I-1502J-1D01*
G02X1632580Y116021I172J102D01*
G01Y149300D01*
G02X1632780Y149500I200J0D01*
G37*
%LPC*%
G75*
G36*
G01X729181Y273202D02*
G02X730600Y273502I1418J-3202D01*
G02Y266498I0J-3502D01*
G02X729181Y266798I-1J3502D01*
G03X729019I-81J-182D01*
G02X727600Y266498I-1418J3202D01*
G02Y273502I0J3502D01*
G02X729019Y273202I1J-3502D01*
G03X729181I81J182D01*
G37*
G36*
G01X1025769Y214158D02*
G02X1024525Y213498I-1244J842D01*
G02Y216502I0J1502D01*
G02X1025769Y215842I0J-1502D01*
G03X1026431I331J224D01*
G02X1027675Y216502I1244J-842D01*
G02Y213498I0J-1502D01*
G02X1026431Y214158I0J1502D01*
G03X1025769I-331J-224D01*
G37*
G36*
G01X1861017Y263900D02*
X1841583D01*
G02X1841441Y263959I0J200D01*
G01X1839459Y265941D01*
G02X1839400Y266083I141J142D01*
G01Y305817D01*
G02X1839459Y305959I200J0D01*
G01X1841741Y308241D01*
G02X1841883Y308300I142J-141D01*
G01X1860717D01*
G02X1860859Y308241I0J-200D01*
G01X1863241Y305859D01*
G02X1863300Y305717I-141J-142D01*
G01Y266183D01*
G02X1863241Y266041I-200J0D01*
G01X1861159Y263959D01*
G02X1861017Y263900I-142J141D01*
G37*
G36*
G01X1765586Y248643D02*
Y248959D01*
G03X1765509Y249116I-200J-1D01*
G02X1764930Y250301I923J1185D01*
G02X1767934I1502J0D01*
G02X1767355Y249116I-1502J0D01*
G03X1767278Y248959I123J-158D01*
G01Y248643D01*
G03X1767355Y248486I200J1D01*
G02X1767934Y247301I-923J-1185D01*
G02X1764930I-1502J0D01*
G02X1765509Y248486I1502J0D01*
G03X1765586Y248643I-123J158D01*
G37*
G36*
G01X1774586Y248699D02*
Y249015D01*
G03X1774509Y249172I-200J-1D01*
G02X1773930Y250357I923J1185D01*
G02X1776934I1502J0D01*
G02X1776355Y249172I-1502J0D01*
G03X1776278Y249015I123J-158D01*
G01Y248699D01*
G03X1776355Y248542I200J1D01*
G02X1776934Y247357I-923J-1185D01*
G02X1773930I-1502J0D01*
G02X1774509Y248542I1502J0D01*
G03X1774586Y248699I-123J158D01*
G37*
G36*
G01X1783086D02*
Y249015D01*
G03X1783009Y249172I-200J-1D01*
G02X1782430Y250357I923J1185D01*
G02X1785434I1502J0D01*
G02X1784855Y249172I-1502J0D01*
G03X1784778Y249015I123J-158D01*
G01Y248699D01*
G03X1784855Y248542I200J1D01*
G02X1785434Y247357I-923J-1185D01*
G02X1782430I-1502J0D01*
G02X1783009Y248542I1502J0D01*
G03X1783086Y248699I-123J158D01*
G37*
G36*
G01X1739517Y256582D02*
Y256918D01*
X1739492Y256985D01*
X1739468Y257013D01*
G02X1739098Y258000I1131J987D01*
G02X1742102I1502J0D01*
G02X1741732Y257013I-1501J0D01*
G01X1741708Y256985D01*
X1741683Y256918D01*
Y256582D01*
X1741708Y256515D01*
X1741732Y256487D01*
G02Y254513I-1131J-987D01*
G01X1741708Y254485D01*
X1741683Y254418D01*
Y254082D01*
X1741708Y254015D01*
X1741732Y253987D01*
G02Y252013I-1131J-987D01*
G01X1741708Y251985D01*
X1741683Y251918D01*
Y251582D01*
X1741708Y251515D01*
X1741732Y251487D01*
G02Y249513I-1131J-987D01*
G01X1741708Y249485D01*
X1741683Y249418D01*
Y249082D01*
X1741708Y249015D01*
X1741732Y248987D01*
G02X1742102Y248000I-1131J-987D01*
G02X1739098I-1502J0D01*
G02X1739468Y248987I1501J0D01*
G01X1739492Y249015D01*
X1739517Y249082D01*
Y249418D01*
X1739492Y249485D01*
X1739468Y249513D01*
G02Y251487I1131J987D01*
G01X1739492Y251515D01*
X1739517Y251582D01*
Y251918D01*
X1739492Y251985D01*
X1739468Y252013D01*
G02Y253987I1131J987D01*
G01X1739492Y254015D01*
X1739517Y254082D01*
Y254418D01*
X1739492Y254485D01*
X1739468Y254513D01*
G02Y256487I1131J987D01*
G01X1739492Y256515D01*
X1739517Y256582D01*
G37*
G36*
G01X1750517D02*
Y256918D01*
X1750492Y256985D01*
X1750468Y257013D01*
G02X1750098Y258000I1131J987D01*
G02X1753102I1502J0D01*
G02X1752732Y257013I-1501J0D01*
G01X1752708Y256985D01*
X1752683Y256918D01*
Y256582D01*
X1752708Y256515D01*
X1752732Y256487D01*
G02Y254513I-1131J-987D01*
G01X1752708Y254485D01*
X1752683Y254418D01*
Y254082D01*
X1752708Y254015D01*
X1752732Y253987D01*
G02Y252013I-1131J-987D01*
G01X1752708Y251985D01*
X1752683Y251918D01*
Y251582D01*
X1752708Y251515D01*
X1752732Y251487D01*
G02Y249513I-1131J-987D01*
G01X1752708Y249485D01*
X1752683Y249418D01*
Y249082D01*
X1752708Y249015D01*
X1752732Y248987D01*
G02X1753102Y248000I-1131J-987D01*
G02X1750098I-1502J0D01*
G02X1750468Y248987I1501J0D01*
G01X1750492Y249015D01*
X1750517Y249082D01*
Y249418D01*
X1750492Y249485D01*
X1750468Y249513D01*
G02Y251487I1131J987D01*
G01X1750492Y251515D01*
X1750517Y251582D01*
Y251918D01*
X1750492Y251985D01*
X1750468Y252013D01*
G02Y253987I1131J987D01*
G01X1750492Y254015D01*
X1750517Y254082D01*
Y254418D01*
X1750492Y254485D01*
X1750468Y254513D01*
G02Y256487I1131J987D01*
G01X1750492Y256515D01*
X1750517Y256582D01*
G37*
G36*
G01X1775915Y355545D02*
X1775958Y355656D01*
G03X1775960Y355796I-186J73D01*
G02X1775873Y356300I1416J504D01*
G02X1778877I1502J0D01*
G02X1778792Y355801I-1502J-1D01*
G03X1778794Y355662I188J-67D01*
G01X1778838Y355550D01*
G03X1778936Y355444I186J74D01*
G02X1780885Y352305I-1553J-3139D01*
G02X1773881I-3502J0D01*
G02X1775818Y355438I3502J0D01*
G03X1775915Y355545I-90J179D01*
G37*
G36*
G01X1773942Y385643D02*
Y428615D01*
G02X1774001Y428757I200J0D01*
G01X1777187Y431943D01*
G02X1777329Y432002I142J-141D01*
G01X1815588D01*
G02X1815730Y431943I0J-200D01*
G01X1843293Y404380D01*
G02X1843352Y404238I-141J-142D01*
G01Y358869D01*
G03X1843410Y358728I200J0D01*
G01X1850656Y351482D01*
G03X1850806Y351423I142J141D01*
G01X1851143Y351437D01*
X1851217Y351473D01*
X1851244Y351506D01*
G02X1853957Y352765I2713J-2294D01*
G02X1857509Y349213I0J-3552D01*
G02X1857326Y348088I-3552J0D01*
G01X1857308Y348034D01*
X1857334Y347924D01*
X1857668Y347590D01*
X1857778Y347564D01*
X1857832Y347582D01*
G02X1858957Y347765I1125J-3369D01*
G02Y340661I0J-3552D01*
G02X1857832Y340844I0J3552D01*
G01X1857778Y340862D01*
X1857668Y340836D01*
X1857334Y340502D01*
X1857308Y340392D01*
X1857326Y340338D01*
G02X1857509Y339213I-3369J-1125D01*
G02X1857326Y338088I-3552J0D01*
G01X1857308Y338034D01*
X1857334Y337924D01*
X1857668Y337590D01*
X1857778Y337564D01*
X1857832Y337582D01*
G02X1858957Y337765I1125J-3369D01*
G02Y330661I0J-3552D01*
G02X1857832Y330844I0J3552D01*
G01X1857778Y330862D01*
X1857668Y330836D01*
X1857334Y330502D01*
X1857308Y330392D01*
X1857326Y330338D01*
G02X1857509Y329213I-3369J-1125D01*
G02X1855986Y326297I-3553J0D01*
G03X1855900Y326133I114J-164D01*
G01Y322293D01*
G03X1855986Y322129I200J0D01*
G02X1857509Y319213I-2030J-2916D01*
G02X1854804Y315764I-3551J0D01*
G01X1854777Y315757D01*
X1854730Y315730D01*
X1852440Y313440D01*
X1852413Y313393D01*
X1852406Y313366D01*
G02X1848957Y310661I-3449J846D01*
G02X1847123Y311171I0J3553D01*
G01X1847099Y311186D01*
X1847047Y311200D01*
X1846883D01*
G02X1846741Y311259I0J200D01*
G01X1840559Y317441D01*
G02X1840500Y317583I141J142D01*
G01Y318397D01*
X1840495Y318419D01*
G02X1840405Y319213I3462J795D01*
G02X1840495Y320007I3552J-1D01*
G01X1840500Y320029D01*
Y322417D01*
G03X1840441Y322559I-200J0D01*
G01X1839560Y323440D01*
G03X1839419Y323498I-141J-142D01*
G01X1809147D01*
G02X1809005Y323557I0J200D01*
G01X1796657Y335905D01*
G02X1796598Y336047I141J142D01*
G01Y375644D01*
G03X1796540Y375785I-200J0D01*
G01X1791904Y380421D01*
G03X1791763Y380480I-142J-141D01*
G01X1779106D01*
G02X1778964Y380538I-1J200D01*
G01X1774001Y385501D01*
G02X1773942Y385643I141J142D01*
G37*
G36*
G01X1629071Y102923D02*
X1628714Y102785D01*
X1628655Y102725D01*
X1628640Y102685D01*
G02X1625370Y100438I-3270J1256D01*
G02Y107442I0J3502D01*
G02X1628444Y105618I0J-3502D01*
G01X1628465Y105580D01*
X1628531Y105529D01*
X1628903Y105440D01*
X1628986Y105455D01*
X1629021Y105479D01*
G02X1629870Y105742I849J-1239D01*
G02Y102738I0J-1502D01*
G02X1629193Y102899I0J1502D01*
G01X1629155Y102918D01*
X1629071Y102923D01*
G37*
G36*
G01X1636464Y101311D02*
G02X1635035Y104134I2074J2823D01*
G02X1638537Y107636I3502J0D01*
G02X1640192Y107220I0J-3502D01*
G03X1640382I95J176D01*
G02X1642037Y107636I1655J-3086D01*
G02X1643692Y107220I0J-3502D01*
G03X1643882I95J176D01*
G02X1645537Y107636I1655J-3086D01*
G02X1649029Y104403I0J-3502D01*
G03X1649110Y104257I199J15D01*
G02X1650038Y103239I-2074J-2822D01*
G03X1650254Y103147I172J103D01*
G02X1651037Y103236I784J-3413D01*
G02Y96232I0J-3502D01*
G02X1648036Y97929I0J3502D01*
G03X1647820Y98021I-172J-103D01*
G02X1647037Y97932I-784J3413D01*
G02X1645382Y98348I0J3502D01*
G03X1645192I-95J-176D01*
G02X1643537Y97932I-1655J3086D01*
G02X1641882Y98348I0J3502D01*
G03X1641692I-95J-176D01*
G02X1640037Y97932I-1655J3086D01*
G02X1636545Y101165I0J3502D01*
G03X1636464Y101311I-199J-15D01*
G37*
G36*
G01X1671219Y117198D02*
G02X1669800Y116898I-1418J3202D01*
G02Y123902I0J3502D01*
G02X1671219Y123602I1J-3502D01*
G03X1671381I81J182D01*
G02X1672800Y123902I1418J-3202D01*
G02X1674219Y123602I1J-3502D01*
G03X1674381I81J182D01*
G02X1675800Y123902I1418J-3202D01*
G02Y116898I0J-3502D01*
G02X1674381Y117198I-1J3502D01*
G03X1674219I-81J-182D01*
G02X1672800Y116898I-1418J3202D01*
G02X1671381Y117198I-1J3502D01*
G03X1671219I-81J-182D01*
G37*
G36*
G01X1653828Y115388D02*
G02X1653548Y116760I3221J1372D01*
G02X1657050Y120262I3502J0D01*
G02X1658564Y119918I0J-3502D01*
G03X1658736I86J180D01*
G02X1660250Y120262I1514J-3158D01*
G02X1663752Y116760I0J-3502D01*
G02X1663472Y115388I-3501J0D01*
G03Y115232I184J-78D01*
G02X1663752Y113860I-3221J-1372D01*
G02X1660250Y110358I-3502J0D01*
G02X1658736Y110702I0J3502D01*
G03X1658564I-86J-180D01*
G02X1657050Y110358I-1514J3158D01*
G02X1654130Y111927I0J3502D01*
G01X1654094Y111981D01*
X1653974Y112027D01*
X1653483Y111896D01*
X1653401Y111797D01*
X1653397Y111732D01*
G02X1650002Y108548I-3395J218D01*
G02X1648328Y108988I-1J3402D01*
G03X1648132I-98J-174D01*
G02X1646458Y108548I-1673J2962D01*
G02X1644785Y108988I0J3401D01*
G03X1644588I-98J-174D01*
G02X1641242I-1673J2961D01*
G03X1641045I-98J-174D01*
G02X1639372Y108548I-1673J2961D01*
G02X1635970Y111950I0J3402D01*
G02X1636181Y113131I3402J1D01*
G03Y113269I-187J69D01*
G02X1635970Y114450I3191J1180D01*
G02X1639372Y117852I3402J0D01*
G02X1641045Y117412I0J-3401D01*
G03X1641242I99J174D01*
G02X1644588I1673J-2961D01*
G03X1644785I99J174D01*
G02X1646458Y117852I1673J-2961D01*
G02X1648132Y117412I1J-3402D01*
G03X1648328I98J174D01*
G02X1650002Y117852I1673J-2962D01*
G02X1653354Y115034I0J-3403D01*
G03X1653740Y115003I197J34D01*
G02X1653828Y115232I3311J-1141D01*
G03Y115388I-184J78D01*
G37*
G36*
G01X1643415Y124542D02*
Y124581D01*
G02X1644917Y123079I1502J0D01*
G02X1644061Y123347I0J1501D01*
G03X1643434Y123008I-227J-329D01*
G01Y122969D01*
G02X1641932Y124471I-1502J0D01*
G02X1642788Y124203I0J-1501D01*
G03X1643415Y124542I227J329D01*
G37*
G36*
G01X1650341Y123940D02*
X1650306Y123973D01*
G02X1649823Y125076I1018J1103D01*
G02X1652827I1502J0D01*
G02X1652079Y123777I-1502J0D01*
G01X1652038Y123753D01*
X1651986Y123674D01*
X1651941Y123259D01*
X1651974Y123170D01*
X1652009Y123137D01*
G02X1652492Y122034I-1018J-1103D01*
G02X1650990Y120532I-1502J0D01*
G02X1649804Y121113I0J1501D01*
G01X1649773Y121153D01*
X1649682Y121193D01*
X1649250Y121163D01*
X1649166Y121110D01*
X1649141Y121066D01*
G02X1647837Y120310I-1304J747D01*
G02Y123314I0J1502D01*
G02X1649023Y122733I0J-1501D01*
G01X1649054Y122693D01*
X1649145Y122653D01*
X1649577Y122683D01*
X1649661Y122736D01*
X1649686Y122780D01*
G02X1650236Y123333I1304J-746D01*
G01X1650277Y123357D01*
X1650329Y123436D01*
X1650374Y123851D01*
X1650341Y123940D01*
G37*
G54D30*
X134600Y134000D03*
X1842164Y419238D03*
Y432338D03*
X1847164Y419238D03*
Y430568D03*
X1837164Y419238D03*
Y428238D03*
X1852164Y419238D03*
X1769692Y334649D03*
X1789600Y247000D03*
X1852164Y435538D03*
X1795600Y308000D03*
X1767700Y346200D03*
X1767600Y350000D03*
X1769300Y329400D03*
Y340600D03*
X1614100Y110000D03*
Y130000D03*
Y115000D03*
Y120000D03*
X1656657Y127365D03*
X1649197Y132915D03*
X1632336Y109117D03*
X1657050Y102380D03*
X1638707Y132954D03*
X1667000Y138000D03*
X1662000Y106000D03*
G54D31*
X441938Y309700D03*
Y265300D03*
Y220900D03*
Y176500D03*
X408100Y180100D03*
Y224500D03*
X441938Y87700D03*
Y132100D03*
X725000Y292500D03*
X1320346Y289900D03*
Y245500D03*
X1355100Y160000D03*
X1355000Y204400D03*
X1320346Y112300D03*
G54D33*
X166785Y230000D03*
X243785D03*
X166785Y310000D03*
X243785D03*
X166785Y390000D03*
X243785D03*
X166785Y470000D03*
X243785D03*
X166785Y550000D03*
X243785D03*
X1488500Y230000D03*
X1565500D03*
X1488500Y310000D03*
X1565500D03*
X1488500Y390000D03*
X1565500D03*
X1488500Y470000D03*
X1565500D03*
X1488500Y550000D03*
X1565500D03*
G54D32*
X166785Y200472D03*
X243785D03*
X166785Y280472D03*
X243785D03*
X166785Y360472D03*
X243785D03*
X166785Y440472D03*
X243785D03*
X166785Y520472D03*
X243785D03*
X1488500Y200472D03*
X1565500D03*
X1488500Y360472D03*
X1565500D03*
X1488500Y440472D03*
X1565500D03*
X1488500Y520472D03*
X1565500D03*
G54D37*
X1856772Y360433D03*
X1851457Y220433D03*
G54D35*
X287402Y628465D03*
X1468504D03*
X1444882Y659961D03*
G54D34*
X393703Y354332D03*
G54D29*
X231600Y81000D03*
G54D36*
X940197Y313484D03*
Y88484D03*
X822087Y313484D03*
Y88484D03*
G54D28*
X59055Y411594D03*
Y236614D03*
X1673228Y411614D03*
Y236614D03*
%LPD*%
G75*
G36*
G01X1778365Y429500D02*
X1814552D01*
G02X1814694Y429441I0J-200D01*
G01X1840791Y403344D01*
G02X1840850Y403202I-141J-142D01*
G01Y357833D01*
G03X1840909Y357691I200J0D01*
G01X1848441Y350159D01*
X1848471Y350069D01*
X1848464Y350022D01*
G03X1848405Y349213I5493J-807D01*
G03X1850524Y344850I5551J0D01*
G01X1850560Y344821D01*
X1850600Y344739D01*
Y343687D01*
X1850560Y343605D01*
X1850524Y343576D01*
G03X1849293Y342225I3432J-4364D01*
G01X1849265Y342181D01*
X1849177Y342133D01*
X1848737D01*
X1848649Y342181D01*
X1848621Y342225D01*
G03X1843957Y344765I-4664J-3012D01*
G03X1838405Y339213I0J-5552D01*
G03X1843273Y333703I5552J0D01*
G02X1843447Y333529I-24J-198D01*
G03X1845945Y329549I5510J684D01*
G01X1845989Y329521D01*
X1846037Y329433D01*
Y328993D01*
X1845989Y328905D01*
X1845945Y328877D01*
G03X1843747Y326131I3012J-4664D01*
G02X1843559Y326000I-188J69D01*
G01X1810183D01*
G02X1810041Y326059I0J200D01*
G01X1799159Y336941D01*
G02X1799100Y337083I141J142D01*
G01Y376680D01*
G03X1799041Y376822I-200J0D01*
G01X1792941Y382922D01*
G03X1792799Y382981I-142J-141D01*
G01X1780142D01*
G02X1780000Y383040I0J200D01*
G01X1776503Y386537D01*
G02X1776444Y386679I141J142D01*
G01Y427579D01*
G02X1776503Y427721I200J0D01*
G01X1778223Y429441D01*
G02X1778365Y429500I142J-141D01*
G37*
G54D10*
G01X1488500Y230000D02*
X1491671Y226829D01*
G01X1485329Y233171D02*
X1488500Y230000D01*
G01D02*
X1491671Y233171D01*
G01X1485329Y226829D02*
X1488500Y230000D01*
G01X1565500D02*
X1568671Y226829D01*
G01X1562329Y233171D02*
X1565500Y230000D01*
G01X1562329Y226829D02*
X1565500Y230000D01*
X3018Y23930D03*
X10493Y5830D03*
X3018Y43930D03*
Y83930D03*
Y63930D03*
Y103930D03*
Y143930D03*
Y123930D03*
Y163930D03*
Y203930D03*
Y183930D03*
Y223930D03*
Y263930D03*
Y243930D03*
Y283930D03*
Y323930D03*
Y303930D03*
Y343930D03*
Y383930D03*
Y363930D03*
Y403930D03*
Y443930D03*
Y423930D03*
Y463930D03*
Y503930D03*
Y483930D03*
Y523930D03*
Y563930D03*
Y543930D03*
Y583930D03*
X15642Y619715D03*
X3018Y603930D03*
X30709Y3014D03*
X35455Y620194D03*
X75455D03*
X55455D03*
X81406Y3042D03*
X101406D03*
X95455Y620194D03*
X121406Y3042D03*
X137355Y120500D03*
X114923Y623982D03*
X124901Y640105D03*
X161406Y3042D03*
X141406D03*
X156785Y101285D03*
X154778Y672779D03*
X181406Y3042D03*
X187600Y106500D03*
X176785Y102000D03*
X194778Y672779D03*
X174778D03*
X201406Y3042D03*
X221406D03*
X205061Y85500D03*
Y79000D03*
Y75000D03*
Y71500D03*
Y67500D03*
X211425Y106075D03*
X205061Y89500D03*
Y93000D03*
Y97000D03*
X225829Y99503D03*
X225953Y95780D03*
X225891Y92305D03*
X210925Y115575D03*
X214778Y672779D03*
X229829Y99503D03*
X233329D03*
X237329D03*
X229953Y95780D03*
X233453D03*
X237453D03*
X229891Y92305D03*
X233391D03*
X237391D03*
X254778Y672779D03*
X234778D03*
X274778D03*
X317000Y58000D03*
Y74475D03*
Y64500D03*
X311956Y651522D03*
X294778Y672779D03*
X321500Y74475D03*
Y66500D03*
X325100Y64000D03*
X332500Y63300D03*
X330500Y74476D03*
X324000Y77000D03*
X326000Y74476D03*
X345412Y435017D03*
Y455017D03*
Y475017D03*
Y495017D03*
Y515017D03*
Y535017D03*
Y555017D03*
Y575017D03*
Y595017D03*
X342119Y613510D03*
X331285Y620008D03*
X362127Y406608D03*
X350024Y418335D03*
X396216Y46875D03*
X399680Y402510D03*
X379680D03*
X428277Y167056D03*
X430608Y211389D03*
X419680Y402510D03*
X454738Y56000D03*
X451738D03*
X448738D03*
X445738D03*
X442738D03*
X454738Y68000D03*
Y65000D03*
Y62000D03*
Y59000D03*
X451738D03*
Y62000D03*
Y65000D03*
Y68000D03*
X448738Y59000D03*
Y62000D03*
Y65000D03*
Y68000D03*
X445738Y59000D03*
Y62000D03*
Y65000D03*
Y68000D03*
X442738Y59000D03*
Y62000D03*
Y65000D03*
Y68000D03*
X454738Y112400D03*
Y109400D03*
Y106400D03*
Y103400D03*
X451738D03*
Y106400D03*
Y109400D03*
Y112400D03*
X448738Y103400D03*
Y106400D03*
Y109400D03*
Y112400D03*
X445738Y103400D03*
Y106400D03*
Y109400D03*
Y112400D03*
X442738Y103400D03*
Y106400D03*
Y109400D03*
Y112400D03*
X454738Y100400D03*
X451738D03*
X448738D03*
X445738D03*
X442738D03*
X454738Y147800D03*
X451738D03*
X448738D03*
X445738D03*
X442738D03*
X454738Y144800D03*
X451738D03*
X448738D03*
X445738D03*
X442738D03*
X454738Y156800D03*
Y153800D03*
Y150800D03*
X451738D03*
Y153800D03*
Y156800D03*
X448738Y150800D03*
Y153800D03*
Y156800D03*
X445738Y150800D03*
Y153800D03*
Y156800D03*
X442738Y150800D03*
Y153800D03*
Y156800D03*
X454738Y201200D03*
Y198200D03*
Y195200D03*
Y192200D03*
X451738D03*
Y195200D03*
Y198200D03*
Y201200D03*
X448738Y192200D03*
Y195200D03*
Y198200D03*
Y201200D03*
X445738Y192200D03*
Y195200D03*
Y198200D03*
Y201200D03*
X442738Y192200D03*
Y195200D03*
Y198200D03*
Y201200D03*
X454738Y189200D03*
X451738D03*
X448738D03*
X445738D03*
X442738D03*
X454738Y239600D03*
Y236600D03*
X451738D03*
Y239600D03*
X448738Y236600D03*
Y239600D03*
X445738Y236600D03*
Y239600D03*
X442738Y236600D03*
Y239600D03*
X454738Y233600D03*
X451738D03*
X448738D03*
X445738D03*
X442738D03*
X454738Y245600D03*
Y242600D03*
X451738D03*
Y245600D03*
X448738Y242600D03*
Y245600D03*
X445738Y242600D03*
Y245600D03*
X442738Y242600D03*
Y245600D03*
X448738Y278000D03*
X451738D03*
X454738D03*
X448738Y290000D03*
Y287000D03*
Y284000D03*
Y281000D03*
X451738Y290000D03*
Y287000D03*
Y284000D03*
Y281000D03*
X454738D03*
Y284000D03*
Y287000D03*
Y290000D03*
X445738D03*
Y287000D03*
Y284000D03*
Y281000D03*
Y278000D03*
X442738Y290000D03*
Y287000D03*
Y284000D03*
Y281000D03*
Y278000D03*
X459680Y402510D03*
X439680D03*
X498923Y37456D03*
X495923D03*
X492923D03*
X489923D03*
X479680Y402510D03*
X501923Y37456D03*
X504923D03*
X510923D03*
X507923D03*
X528084Y77900D03*
Y74900D03*
Y71900D03*
Y68900D03*
Y65900D03*
X525084Y77900D03*
Y74900D03*
Y71900D03*
Y68900D03*
Y65900D03*
X522084Y77900D03*
Y74900D03*
Y71900D03*
Y68900D03*
Y65900D03*
X525084Y116300D03*
Y113300D03*
Y110300D03*
X522084Y113300D03*
Y116300D03*
Y110300D03*
X528084Y116300D03*
Y113300D03*
Y110300D03*
X525084Y122300D03*
X522084D03*
X525084Y119300D03*
X522084D03*
X528084Y122300D03*
Y119300D03*
X525084Y166700D03*
X522084D03*
X525084Y160700D03*
Y163700D03*
Y157700D03*
Y154700D03*
X522084Y157700D03*
Y163700D03*
Y160700D03*
Y154700D03*
Y199100D03*
Y205100D03*
Y208100D03*
Y202100D03*
X525084Y199100D03*
Y202100D03*
Y208100D03*
Y205100D03*
X522084Y211100D03*
X525084D03*
X522084Y243500D03*
Y249500D03*
Y252500D03*
Y246500D03*
X525084Y243500D03*
Y246500D03*
Y252500D03*
Y249500D03*
X522084Y255500D03*
X525084D03*
X528084Y243500D03*
Y246500D03*
Y252500D03*
Y249500D03*
Y255500D03*
Y299900D03*
X525084D03*
X522084D03*
X528084Y296900D03*
X525084D03*
X522084D03*
X528084Y293900D03*
X525084D03*
X522084D03*
X528084Y290900D03*
Y287900D03*
X525084D03*
Y290900D03*
X522084D03*
Y287900D03*
X506309Y329000D03*
Y322000D03*
X499680Y402510D03*
X519680D03*
X531084Y77900D03*
Y74900D03*
Y71900D03*
Y68900D03*
Y65900D03*
X551430Y132400D03*
Y265600D03*
X531084Y299900D03*
Y296900D03*
Y293900D03*
Y290900D03*
Y287900D03*
X539680Y402510D03*
X559680D03*
X586184Y117800D03*
X583184D03*
X580184D03*
X586184Y114800D03*
X583184D03*
X580184D03*
X586184Y111800D03*
X583184D03*
X580184D03*
X586184Y108800D03*
X583184D03*
X580184D03*
X586184Y105800D03*
X583184D03*
X580184D03*
X563007Y118477D03*
Y114123D03*
X580184Y126800D03*
X583184D03*
X586184D03*
Y123800D03*
X583184D03*
X580184D03*
X586184Y120800D03*
X583184D03*
X580184D03*
X574230Y132400D03*
X583184Y239000D03*
X580184D03*
X563007Y251677D03*
X576467Y265600D03*
X563007Y247323D03*
X583184Y242000D03*
X580184D03*
X583184Y254000D03*
Y251000D03*
Y248000D03*
Y245000D03*
X580184D03*
Y248000D03*
Y251000D03*
Y254000D03*
X583184Y260000D03*
Y257000D03*
X580184D03*
Y260000D03*
X562830Y270000D03*
Y266500D03*
X590298Y282890D03*
X562830Y277000D03*
X590298Y276984D03*
X562830Y273500D03*
X565091Y302592D03*
X570443Y302702D03*
X579680Y402510D03*
X605700Y259500D03*
X612684Y297000D03*
X616684Y294500D03*
X602928Y293969D03*
X600875Y295937D03*
X608259Y305000D03*
X619680Y402510D03*
X599680D03*
X645784Y43500D03*
X648784D03*
X645784Y40500D03*
X648784D03*
X645784Y99000D03*
X648784D03*
X645784Y96000D03*
X648784D03*
X639010Y236377D03*
X632186Y338917D03*
X623500Y379000D03*
X639680Y402510D03*
X651784Y43500D03*
Y40500D03*
X657784D03*
X654784D03*
X657784Y43500D03*
X654784D03*
X651784Y99000D03*
Y96000D03*
X657784D03*
X654784D03*
X657784Y99000D03*
X654784D03*
X664484Y212500D03*
X666984D03*
X672484D03*
X674984D03*
X679484D03*
X657259Y263000D03*
X674800Y269600D03*
X660684Y262500D03*
X654100Y263000D03*
X670184Y288500D03*
X662184Y280500D03*
X662100Y304500D03*
X658925Y320000D03*
X659680Y402510D03*
X679680D03*
X681984Y212500D03*
X685484D03*
X687984D03*
X683592Y259908D03*
X688945Y259761D03*
X695259Y248020D03*
X706984Y261100D03*
X710084D03*
X692109Y248020D03*
X710900Y324100D03*
X691759Y309000D03*
X699680Y402510D03*
X736554Y131056D03*
Y128056D03*
X739554Y131056D03*
Y128056D03*
X742554D03*
X732100Y185000D03*
X729100D03*
X726100D03*
X720100D03*
X723100D03*
X726100Y188000D03*
X729100D03*
X732100D03*
X723100D03*
X720100D03*
X726000Y231500D03*
X729000D03*
X723000D03*
X720000D03*
X732000D03*
Y228500D03*
X720000D03*
X723000D03*
X726000D03*
X729000D03*
X722925Y299500D03*
X719433Y328087D03*
X717401Y329996D03*
X739680Y402510D03*
X719680D03*
X742554Y131056D03*
X770700Y206900D03*
X749600Y185000D03*
X752600D03*
X755600D03*
X758600D03*
X746600Y188000D03*
X758600D03*
X755600D03*
X752600D03*
X749600D03*
X746600Y185000D03*
X758500Y231500D03*
X746500D03*
X755500D03*
X752500D03*
X749500D03*
X746500Y228500D03*
X755500D03*
X752500D03*
X749500D03*
X758500D03*
X759680Y402510D03*
X776000Y206600D03*
X779680Y402510D03*
X799680D03*
X819680D03*
X862600Y29500D03*
X839680Y402510D03*
X859680D03*
X867100Y28000D03*
X872533Y29432D03*
X867100Y31500D03*
X887500Y355680D03*
X885100Y361500D03*
X885265Y381000D03*
X878175Y374100D03*
Y364709D03*
X879680Y402510D03*
X919680D03*
X899680D03*
X894500Y396500D03*
X954200Y200200D03*
X954600Y207200D03*
X939680Y402510D03*
X983500Y185000D03*
Y188000D03*
X980500Y185000D03*
X974500D03*
X977500D03*
X980500Y188000D03*
X977500D03*
X974500D03*
Y231500D03*
X977500D03*
X983500D03*
X980500D03*
X983500Y228500D03*
X980500D03*
X977500D03*
X974500D03*
X978600Y310955D03*
X959680Y402510D03*
X979680D03*
X990954Y131056D03*
Y128056D03*
X993954Y131056D03*
Y128056D03*
X996954D03*
Y131056D03*
X986500Y185000D03*
Y188000D03*
X1004000Y185000D03*
X1001000Y188000D03*
X1004000D03*
X1007000Y185000D03*
X1010000D03*
X1013000D03*
Y188000D03*
X1010000D03*
X1007000D03*
X1001000Y185000D03*
X1004000Y231500D03*
X1007000D03*
X1010000D03*
X1001000D03*
X986500D03*
X1013000D03*
X986500Y228500D03*
X1013000D03*
X1004000D03*
X1007000D03*
X1010000D03*
X1001000D03*
X999680Y402510D03*
X1030100Y207500D03*
X1017300Y322500D03*
X1026270Y303729D03*
X1023492Y346593D03*
X1021414Y355979D03*
X1017300Y385600D03*
X1039680Y402510D03*
X1019680D03*
X1074500Y43500D03*
Y99000D03*
X1070525Y243000D03*
X1052200Y290900D03*
X1055300D03*
X1073339Y292239D03*
X1070175Y303980D03*
X1067025D03*
X1059680Y402510D03*
X1077500Y43500D03*
Y40500D03*
X1074500D03*
X1080500D03*
X1083500D03*
X1086500D03*
X1080500Y43500D03*
X1083500D03*
X1086500D03*
X1077500Y99000D03*
Y96000D03*
X1074500D03*
X1080500D03*
X1083500D03*
X1086500D03*
X1080500Y99000D03*
X1083500D03*
X1086500D03*
X1092100Y263500D03*
X1100500D03*
X1100100Y247500D03*
X1101500Y271500D03*
X1088079Y274980D03*
X1087100Y282500D03*
X1101600Y289500D03*
X1080600Y294000D03*
X1094500Y355600D03*
Y360500D03*
X1079680Y402510D03*
X1099680D03*
X1129800Y265400D03*
X1108100Y289000D03*
X1105025D03*
X1124600Y271425D03*
X1123100Y319500D03*
X1123400Y356300D03*
X1119680Y402510D03*
X1155366Y38982D03*
X1152366D03*
X1158366D03*
X1161366D03*
X1145600Y257500D03*
X1149600Y255000D03*
X1160990Y252134D03*
X1140100Y244000D03*
X1154025Y247000D03*
X1163266Y255311D03*
X1156509Y295396D03*
X1141500Y347500D03*
X1138500D03*
X1166000Y352500D03*
X1163000D03*
X1153500Y342500D03*
X1159680Y402510D03*
X1139680D03*
X1176100Y105800D03*
Y108800D03*
X1182100Y105800D03*
Y108800D03*
X1179100D03*
Y105800D03*
X1176100Y111800D03*
Y114800D03*
Y117800D03*
X1182100Y111800D03*
Y114800D03*
Y117800D03*
X1179100D03*
Y114800D03*
Y111800D03*
X1176100Y126800D03*
Y123800D03*
Y120800D03*
X1182100Y126800D03*
Y123800D03*
Y120800D03*
X1179100D03*
Y123800D03*
Y126800D03*
X1187700Y132400D03*
X1176100Y239000D03*
X1171600Y238000D03*
X1179100Y239000D03*
X1182100D03*
X1187700Y265600D03*
X1176100Y254000D03*
Y251000D03*
Y248000D03*
Y245000D03*
Y257000D03*
Y260000D03*
Y242000D03*
X1171600Y241500D03*
X1179100Y242000D03*
Y260000D03*
Y257000D03*
Y245000D03*
Y248000D03*
Y251000D03*
Y254000D03*
X1182100D03*
Y251000D03*
Y248000D03*
Y245000D03*
Y257000D03*
Y260000D03*
Y242000D03*
X1171986Y269110D03*
Y275016D03*
X1178900Y359620D03*
X1179500Y350000D03*
Y355000D03*
X1179680Y402510D03*
X1223866Y38482D03*
X1220866D03*
X1199277Y118477D03*
Y114123D03*
X1210500Y132400D03*
X1199277Y247323D03*
X1210500Y265600D03*
X1199277Y251677D03*
X1199100Y270000D03*
Y266500D03*
Y277000D03*
Y273500D03*
X1201037Y318912D03*
X1197127Y314264D03*
X1199680Y402510D03*
X1219680D03*
X1226866Y38482D03*
X1229866D03*
X1240200Y77900D03*
Y74900D03*
Y71900D03*
Y68900D03*
Y65900D03*
X1237200D03*
Y68900D03*
Y71900D03*
Y74900D03*
Y77900D03*
X1234200Y65900D03*
Y68900D03*
Y71900D03*
Y74900D03*
Y77900D03*
X1231200Y65900D03*
Y68900D03*
Y71900D03*
Y74900D03*
Y77900D03*
X1234200Y116300D03*
Y113300D03*
Y110300D03*
X1237200Y116300D03*
Y113300D03*
Y110300D03*
X1240200D03*
Y113300D03*
Y116300D03*
X1234200Y122300D03*
Y119300D03*
X1237200Y122300D03*
Y119300D03*
X1240200D03*
Y122300D03*
X1237200Y166700D03*
Y163700D03*
Y160700D03*
Y157700D03*
Y154700D03*
X1240200D03*
Y157700D03*
Y160700D03*
Y163700D03*
Y166700D03*
X1237200Y205100D03*
Y202100D03*
Y199100D03*
Y208100D03*
X1240200D03*
Y199100D03*
Y202100D03*
Y205100D03*
X1237200Y211100D03*
X1240200D03*
X1234200Y249500D03*
Y246500D03*
Y243500D03*
Y252500D03*
X1237200Y249500D03*
Y246500D03*
Y243500D03*
Y252500D03*
X1234200Y255500D03*
X1237200D03*
X1240200Y252500D03*
Y243500D03*
Y246500D03*
Y249500D03*
Y255500D03*
Y293900D03*
Y290900D03*
Y287900D03*
Y299900D03*
Y296900D03*
X1237200D03*
Y287900D03*
Y290900D03*
Y293900D03*
Y299900D03*
X1234200Y296900D03*
Y287900D03*
Y290900D03*
Y293900D03*
Y299900D03*
X1231200Y293900D03*
Y290900D03*
Y287900D03*
Y296900D03*
Y299900D03*
X1255975Y330000D03*
Y337000D03*
X1239680Y402510D03*
X1264366Y38482D03*
X1261366D03*
X1267366D03*
X1270366D03*
X1259680Y402510D03*
X1279680D03*
X1313366Y38482D03*
X1307366D03*
X1310366D03*
X1307700Y78900D03*
Y81900D03*
X1310700D03*
Y78900D03*
X1313700Y81900D03*
Y78900D03*
X1307700Y84900D03*
Y87900D03*
X1310700D03*
Y84900D03*
X1313700Y87900D03*
Y84900D03*
X1307700Y90900D03*
X1310700D03*
X1313700D03*
X1307700Y123300D03*
Y126300D03*
X1310700D03*
Y123300D03*
X1313700Y126300D03*
Y123300D03*
X1307700Y129300D03*
Y132300D03*
Y135300D03*
X1310700D03*
Y132300D03*
Y129300D03*
X1313700Y135300D03*
Y132300D03*
Y129300D03*
Y167700D03*
Y170700D03*
Y173700D03*
Y176700D03*
X1310700Y167700D03*
Y170700D03*
Y173700D03*
Y176700D03*
X1307700D03*
Y173700D03*
Y170700D03*
Y167700D03*
X1313700Y179700D03*
X1310700D03*
X1307700D03*
Y212100D03*
Y215100D03*
X1310700D03*
Y212100D03*
X1313700Y215100D03*
Y212100D03*
X1307700Y218100D03*
Y221100D03*
Y224100D03*
X1310700D03*
Y221100D03*
Y218100D03*
X1313700Y224100D03*
Y221100D03*
Y218100D03*
X1307700Y256500D03*
Y259500D03*
X1310700D03*
Y256500D03*
X1313700Y259500D03*
Y256500D03*
X1307700Y262500D03*
Y265500D03*
Y268500D03*
X1310700D03*
Y265500D03*
Y262500D03*
X1313700Y268500D03*
Y265500D03*
Y262500D03*
X1307700Y300900D03*
Y303900D03*
X1310700D03*
Y300900D03*
X1313700Y303900D03*
Y300900D03*
X1307700Y306900D03*
Y309900D03*
Y312900D03*
X1310700D03*
Y309900D03*
Y306900D03*
X1313700Y309900D03*
Y306900D03*
X1299680Y402510D03*
X1316366Y38482D03*
X1316700Y81900D03*
Y78900D03*
X1319700Y81900D03*
Y78900D03*
X1316700Y87900D03*
Y84900D03*
X1319700Y87900D03*
Y84900D03*
X1316700Y90900D03*
X1319700D03*
X1316700Y126300D03*
Y123300D03*
X1319700Y126300D03*
Y123300D03*
X1316700Y135300D03*
Y132300D03*
Y129300D03*
X1319700Y135300D03*
Y132300D03*
Y129300D03*
X1334140Y146642D03*
X1319700Y167700D03*
Y170700D03*
Y173700D03*
Y176700D03*
X1316700Y167700D03*
Y170700D03*
Y173700D03*
Y176700D03*
X1332671Y190644D03*
X1316700Y215100D03*
Y212100D03*
X1319700Y215100D03*
Y212100D03*
X1316700Y224100D03*
Y221100D03*
Y218100D03*
X1319700Y224100D03*
Y221100D03*
Y218100D03*
X1316700Y259500D03*
Y256500D03*
X1319700Y259500D03*
Y256500D03*
X1316700Y268500D03*
Y265500D03*
Y262500D03*
X1319700Y268500D03*
Y265500D03*
Y262500D03*
X1316700Y303900D03*
Y300900D03*
X1319700Y303900D03*
Y300900D03*
X1316700Y306900D03*
X1339680Y402510D03*
X1319680D03*
X1355310Y38893D03*
X1352310D03*
X1349310D03*
X1358310D03*
X1359620Y402940D03*
X1386882Y434539D03*
Y454539D03*
Y474539D03*
Y494539D03*
Y514539D03*
Y534539D03*
Y554539D03*
Y574539D03*
Y594539D03*
X1389643Y612723D03*
X1403035Y620181D03*
X1420335Y635388D03*
Y655388D03*
X1428754Y670547D03*
X1445829Y672778D03*
X1465829D03*
X1494728Y83500D03*
X1490000Y80500D03*
X1499228Y74500D03*
X1485829Y672778D03*
X1508460Y3003D03*
X1503728Y74477D03*
X1527100Y98925D03*
X1524600Y111500D03*
X1505829Y672778D03*
X1525829D03*
X1548460Y3003D03*
X1528460D03*
X1545829Y672778D03*
X1588460Y3003D03*
X1568460D03*
X1567500Y67000D03*
X1565829Y672778D03*
X1585829D03*
X1608460Y3003D03*
X1614100Y125000D03*
X1618100Y148925D03*
X1613527Y627220D03*
X1607226Y650448D03*
X1602599Y667628D03*
X1648460Y3003D03*
X1628460D03*
X1622295Y114940D03*
X1631323Y115140D03*
X1624500Y142500D03*
Y146000D03*
X1622295Y118940D03*
X1636600Y173500D03*
X1622100Y155931D03*
X1626000Y163500D03*
Y167500D03*
X1626925Y156000D03*
X1629000Y175000D03*
X1624000Y189000D03*
X1642000Y184500D03*
X1645000D03*
X1628658Y620261D03*
X1648675Y620226D03*
X1658500Y138000D03*
X1664000Y202500D03*
X1661500Y199000D03*
X1667600Y198500D03*
X1658000Y179500D03*
X1668675Y620226D03*
X1708460Y3003D03*
X1692000Y76570D03*
X1695500Y76500D03*
X1696600Y119000D03*
X1682500Y121825D03*
X1705100Y140500D03*
X1707100Y142500D03*
X1702600Y171500D03*
X1701000Y159000D03*
Y164500D03*
X1685975Y186500D03*
X1688692Y620191D03*
X1708692D03*
X1729255Y25347D03*
Y45347D03*
X1732786Y58461D03*
X1719075Y107016D03*
Y112000D03*
X1738000Y124500D03*
X1714100Y144925D03*
X1715525Y168500D03*
X1728475Y175000D03*
X1721500Y205000D03*
X1721600Y194760D03*
Y198500D03*
X1728600Y387500D03*
X1731100D03*
X1733600D03*
Y397500D03*
X1731100D03*
X1728600D03*
X1729275Y562751D03*
Y542751D03*
Y582751D03*
Y602751D03*
X1753635Y69037D03*
X1767525Y114016D03*
X1767425Y107000D03*
X1764100Y119500D03*
X1751600Y238000D03*
Y235500D03*
X1740600D03*
Y238000D03*
X1751600Y233000D03*
X1740600D03*
X1766447Y239798D03*
Y242798D03*
X1751600Y240500D03*
X1740600D03*
X1762454Y320347D03*
X1742109Y345235D03*
Y342435D03*
X1747416Y348293D03*
X1751289Y345227D03*
X1747909Y345335D03*
Y342535D03*
X1744909Y345335D03*
Y342535D03*
X1747416Y351817D03*
X1747235Y355989D03*
Y359564D03*
X1742109Y339635D03*
Y336835D03*
Y334035D03*
X1747909Y339735D03*
Y336935D03*
Y334135D03*
X1744909Y339735D03*
Y336935D03*
Y334135D03*
X1767151Y333311D03*
X1747235Y363689D03*
Y367264D03*
Y371389D03*
Y374964D03*
X1755454Y515746D03*
X1793635Y69037D03*
X1773635D03*
X1773000Y142525D03*
X1773500Y129500D03*
X1773000Y158000D03*
X1772600Y177300D03*
X1800100Y187500D03*
X1778000Y189500D03*
X1783947Y239798D03*
Y242798D03*
X1775447Y239798D03*
Y242798D03*
X1789600Y243500D03*
X1777532Y328322D03*
X1777459Y332322D03*
X1777383Y348288D03*
X1776100Y361500D03*
Y371500D03*
Y368500D03*
X1776140Y364405D03*
X1784035Y389535D03*
X1781535D03*
X1784035Y386935D03*
X1781535D03*
X1778838Y389508D03*
Y386908D03*
X1781535Y402935D03*
X1784035D03*
X1778838Y402908D03*
X1781535Y405535D03*
X1784035D03*
X1778838Y405508D03*
X1775454Y515746D03*
X1813635Y69037D03*
X1817500Y188000D03*
X1809600Y195000D03*
X1811500Y186000D03*
X1815454Y515746D03*
X1853635Y69037D03*
X1833635D03*
X1844500Y416500D03*
X1847500Y437000D03*
X1835454Y515746D03*
X1855509Y515697D03*
X1871008Y117112D03*
X1871009Y93913D03*
X1871008Y137112D03*
Y177112D03*
Y157112D03*
Y197112D03*
Y237112D03*
Y217112D03*
Y257112D03*
Y297112D03*
Y277112D03*
Y317112D03*
Y357112D03*
Y337112D03*
Y377112D03*
Y417112D03*
Y397112D03*
Y437112D03*
Y477112D03*
Y457112D03*
Y497112D03*
G54D11*
X32284Y541339D03*
X59055Y498032D03*
X1673228D03*
X1700000Y541339D03*
G54D20*
X1835739Y99212D03*
X1835738Y481693D03*
G54D21*
X1846142Y230433D03*
Y240433D03*
X1856772D03*
Y230433D03*
X1846142Y250433D03*
Y260433D03*
X1856772D03*
Y250433D03*
X1843957Y329213D03*
X1858957Y324213D03*
Y314213D03*
X1848957Y344213D03*
X1843957Y349213D03*
G36*
G01X37224Y31090D02*
G02X57265Y31089I10021J6311D01*
G03X55150Y23763I11632J-7326D01*
G01Y17716D01*
G02X39338I-7906J0D01*
G01Y23763D01*
G03X37224Y31090I-13749J2D01*
G37*
G36*
G01Y344082D02*
G02X57265Y344081I10021J6311D01*
G03X55150Y336755I11632J-7326D01*
G01Y330708D01*
G02X39338I-7906J0D01*
G01Y336755D01*
G03X37224Y344082I-13749J2D01*
G37*
G36*
G01X269508Y66522D02*
G02X289549Y66521I10021J6311D01*
G03X287434Y59195I11632J-7326D01*
G01Y53148D01*
G02X271622I-7906J0D01*
G01Y59195D01*
G03X269508Y66522I-13749J2D01*
G37*
G36*
G01X738012Y78335D02*
G02X758053Y78334I10021J6311D01*
G03X755938Y71008I11632J-7326D01*
G01Y64961D01*
G02X740126I-7906J0D01*
G01Y71008D01*
G03X738012Y78335I-13749J2D01*
G37*
G36*
G01X974232D02*
G02X994273Y78334I10021J6311D01*
G03X992158Y71008I11632J-7326D01*
G01Y64961D01*
G02X976346I-7906J0D01*
G01Y71008D01*
G03X974232Y78335I-13749J2D01*
G37*
G36*
G01X1675020Y344082D02*
G02X1695061Y344081I10021J6311D01*
G03X1692946Y336755I11632J-7326D01*
G01Y330708D01*
G02X1677134I-7906J0D01*
G01Y336755D01*
G03X1675020Y344082I-13749J2D01*
G37*
G36*
G01X1789192Y109831D02*
G02X1809233Y109830I10021J6311D01*
G03X1807118Y102504I11632J-7326D01*
G01Y96457D01*
G02X1791306I-7906J0D01*
G01Y102504D01*
G03X1789192Y109831I-13749J2D01*
G37*
G36*
G01Y491720D02*
G02X1809233Y491719I10021J6311D01*
G03X1807118Y484393I11632J-7326D01*
G01Y478346D01*
G02X1791306I-7906J0D01*
G01Y484393D01*
G03X1789192Y491720I-13749J2D01*
G37*
G54D22*
G01X1463274Y11288D02*
X1466712D01*
X1468873Y9127D01*
G01X695259Y248020D02*
X694407Y248872D01*
Y250855D01*
X692529Y252733D01*
X662599D01*
X640697Y230831D01*
X637834D01*
X624486Y244179D01*
X612483D01*
X598203Y258459D01*
Y284799D01*
X584657Y298345D01*
X559453D01*
X531553Y326245D01*
X509064D01*
X506309Y329000D01*
G01X692109Y248020D02*
X692907Y248818D01*
Y250233D01*
X691907Y251233D01*
X663221D01*
X641319Y229331D01*
X637212D01*
X623864Y242679D01*
X611861D01*
X596703Y257837D01*
Y284177D01*
X584035Y296845D01*
X558831D01*
X530931Y324745D01*
X509054D01*
X506309Y322000D01*
G01X1255975Y337000D02*
X1258643Y334332D01*
X1260705D01*
X1261705Y335332D01*
Y336747D01*
X1259088Y339364D01*
X1246652D01*
X1243769Y336481D01*
X1099605D01*
X1069347Y306223D01*
Y304808D01*
X1070175Y303980D01*
G01X1255975Y330000D02*
X1258807Y332832D01*
X1261327D01*
X1263205Y334710D01*
Y337369D01*
X1259710Y340864D01*
X1246030D01*
X1243147Y337981D01*
X1098656D01*
X1067616Y306941D01*
Y304571D01*
X1067025Y303980D01*
G54D13*
G01X428277Y167056D02*
X430441Y164892D01*
X469981D01*
X480435Y175346D01*
Y313634D01*
X501964Y335163D01*
X532520D01*
X565091Y302592D01*
G01X570443Y302702D02*
Y305460D01*
X535343Y340560D01*
X499977D01*
X474603Y315186D01*
Y214122D01*
X470012Y209531D01*
X432466D01*
X430608Y211389D01*
G01X1201037Y318912D02*
X1206888Y324763D01*
X1282413D01*
X1288969Y318207D01*
Y194649D01*
X1292974Y190644D01*
X1332671D01*
G01X1197127Y314264D02*
X1198143Y313248D01*
X1205346D01*
X1211627Y319529D01*
X1277918D01*
X1282814Y314633D01*
Y153080D01*
X1289252Y146642D01*
X1334140D01*
X45275Y236614D03*
Y411594D03*
X72835Y236614D03*
X68898Y226771D03*
X59055Y222834D03*
X49212Y226771D03*
X68898Y246457D03*
X49212D03*
X59055Y250394D03*
X68898Y421437D03*
X72835Y411594D03*
X68898Y401751D03*
X59055Y397814D03*
X49212Y401751D03*
Y421437D03*
X59055Y425374D03*
X1673228Y222834D03*
X1663385Y226771D03*
X1659448Y236614D03*
X1663385Y246457D03*
X1673228Y250394D03*
Y397834D03*
X1663385Y401771D03*
X1659448Y411614D03*
X1663385Y421457D03*
X1673228Y425394D03*
X1687008Y236614D03*
X1683071Y226771D03*
Y246457D03*
Y421457D03*
X1687008Y411614D03*
X1683071Y401771D03*
G54D23*
G01X674800Y269600D02*
X667700Y262500D01*
X660684D01*
G54D14*
X137303Y601693D03*
Y609567D03*
Y617441D03*
Y625315D03*
Y633189D03*
Y641063D03*
Y648937D03*
Y656811D03*
Y664685D03*
X163878Y601693D03*
X156004D03*
X145177D03*
X163878Y609567D03*
Y617441D03*
Y625315D03*
Y633189D03*
X156004Y609567D03*
Y617441D03*
Y625315D03*
Y633189D03*
X145177Y609567D03*
Y617441D03*
Y625315D03*
Y633189D03*
X163878Y641063D03*
Y648937D03*
Y656811D03*
X156004Y641063D03*
Y648937D03*
Y656811D03*
X145177Y641063D03*
Y648937D03*
Y656811D03*
X163878Y664685D03*
X156004D03*
X145177D03*
X192126Y633189D03*
Y625315D03*
Y617441D03*
Y656811D03*
Y648937D03*
Y664685D03*
X200000Y633189D03*
Y625315D03*
Y617441D03*
X215748Y633189D03*
Y625315D03*
Y617441D03*
X223622Y633189D03*
Y625315D03*
Y617441D03*
X215748Y656811D03*
Y648937D03*
X223622Y656811D03*
Y648937D03*
X200000Y656811D03*
Y648937D03*
X215748Y664685D03*
X223622D03*
X200000D03*
X250866Y20827D03*
X255906Y617441D03*
X248032D03*
X255906Y625315D03*
Y633189D03*
X248032D03*
Y625315D03*
X255906Y648937D03*
X248032D03*
X255906Y656811D03*
X248032D03*
X255906Y664685D03*
X248032D03*
X279646Y23012D03*
Y13012D03*
X274646Y18012D03*
X284646Y8012D03*
X274646D03*
X260866Y20827D03*
X279528Y617441D03*
X271654D03*
X279528Y625315D03*
Y633189D03*
X271654D03*
Y625315D03*
X279528Y648937D03*
X271654D03*
X279528Y656811D03*
X271654D03*
X279528Y664685D03*
X271654D03*
X289646Y23012D03*
X295276Y617441D03*
Y625315D03*
Y633189D03*
X303150D03*
Y625315D03*
Y617441D03*
Y648937D03*
X295276D03*
X303150Y656811D03*
X295276D03*
X303150Y664685D03*
X295276D03*
X1437008Y617441D03*
X1429134D03*
X1437008Y625315D03*
Y633189D03*
X1429134D03*
Y625315D03*
X1437008Y648937D03*
X1429134D03*
X1437008Y656811D03*
X1429134D03*
X1437008Y664685D03*
X1429134D03*
X1460630Y617441D03*
X1452756D03*
X1460630Y625315D03*
Y633189D03*
X1452756D03*
Y625315D03*
X1460630Y648937D03*
X1452756D03*
X1460630Y656811D03*
X1452756D03*
X1460630Y664685D03*
X1452756D03*
X1480197Y23012D03*
X1475197Y8012D03*
X1476378Y617441D03*
Y625315D03*
Y633189D03*
X1484252D03*
Y625315D03*
Y617441D03*
Y648937D03*
X1476378D03*
X1484252Y656811D03*
X1476378D03*
X1484252Y664685D03*
X1476378D03*
X1508661Y633189D03*
Y625315D03*
Y617441D03*
X1516535Y633189D03*
Y625315D03*
Y617441D03*
X1508661Y656811D03*
Y648937D03*
X1516535Y656811D03*
Y648937D03*
X1508661Y664685D03*
X1516535D03*
X1532283Y633189D03*
Y625315D03*
Y617441D03*
X1540157Y633189D03*
Y625315D03*
Y617441D03*
X1532283Y656811D03*
Y648937D03*
X1540157Y656811D03*
Y648937D03*
X1532283Y664685D03*
X1540157D03*
X1587107Y601693D03*
X1576280D03*
X1568406D03*
X1587107Y609567D03*
Y617441D03*
Y625315D03*
Y633189D03*
X1576280Y609567D03*
Y617441D03*
Y625315D03*
Y633189D03*
X1568406Y609567D03*
Y617441D03*
Y625315D03*
Y633189D03*
X1587107Y641063D03*
Y648937D03*
Y656811D03*
X1576280Y641063D03*
Y648937D03*
Y656811D03*
X1568406Y641063D03*
Y648937D03*
Y656811D03*
X1587107Y664685D03*
X1576280D03*
X1568406D03*
X1594981Y601693D03*
Y609567D03*
Y617441D03*
Y625315D03*
Y633189D03*
Y641063D03*
Y648937D03*
Y656811D03*
Y664685D03*
G54D24*
G01X163614Y226829D02*
X166785Y230000D01*
G01D02*
X169956Y233171D01*
G01X163614D02*
X166785Y230000D01*
G01D02*
X169956Y226829D01*
G01X163614Y306829D02*
X166785Y310000D01*
G01D02*
X169956Y313171D01*
G01X163614D02*
X166785Y310000D01*
G01D02*
X169956Y306829D01*
G01X163614Y386829D02*
X166785Y390000D01*
G01D02*
X169956Y393171D01*
G01X163614D02*
X166785Y390000D01*
G01D02*
X169956Y386829D01*
G01X163614Y466829D02*
X166785Y470000D01*
G01D02*
X169956Y473171D01*
G01X163614D02*
X166785Y470000D01*
G01D02*
X169956Y466829D01*
G01X163614Y546829D02*
X166785Y550000D01*
G01D02*
X169956Y553171D01*
G01X163614D02*
X166785Y550000D01*
G01D02*
X169956Y546829D01*
G01X240614Y226829D02*
X243785Y230000D01*
G01D02*
X246956Y233171D01*
G01X240614D02*
X243785Y230000D01*
G01D02*
X246956Y226829D01*
G01X240614Y306829D02*
X243785Y310000D01*
G01D02*
X246956Y313171D01*
G01X240614D02*
X243785Y310000D01*
G01D02*
X246956Y306829D01*
G01X240614Y386829D02*
X243785Y390000D01*
G01D02*
X246956Y393171D01*
G01X240614D02*
X243785Y390000D01*
G01D02*
X246956Y386829D01*
G01X240614Y466829D02*
X243785Y470000D01*
G01D02*
X246956Y473171D01*
G01X240614D02*
X243785Y470000D01*
G01D02*
X246956Y466829D01*
G01X240614Y546829D02*
X243785Y550000D01*
G01D02*
X246956Y553171D01*
G01X240614D02*
X243785Y550000D01*
G01D02*
X246956Y546829D01*
G01X1485329Y306829D02*
X1488500Y310000D01*
G01D02*
X1491671Y313171D01*
G01X1485329D02*
X1488500Y310000D01*
G01D02*
X1491671Y306829D01*
G01X1485329Y386829D02*
X1488500Y390000D01*
G01D02*
X1491671Y393171D01*
G01X1485329D02*
X1488500Y390000D01*
G01D02*
X1491671Y386829D01*
G01X1485329Y466829D02*
X1488500Y470000D01*
G01D02*
X1491671Y473171D01*
G01X1485329D02*
X1488500Y470000D01*
G01D02*
X1491671Y466829D01*
G01X1485329Y546829D02*
X1488500Y550000D01*
G01D02*
X1491671Y553171D01*
G01X1485329D02*
X1488500Y550000D01*
G01D02*
X1491671Y546829D01*
G01X1562329Y306829D02*
X1565500Y310000D01*
G01D02*
X1568671Y313171D01*
G01X1562329D02*
X1565500Y310000D01*
G01D02*
X1568671Y306829D01*
G01X1562329Y386829D02*
X1565500Y390000D01*
G01D02*
X1568671Y393171D01*
G01X1562329D02*
X1565500Y390000D01*
G01D02*
X1568671Y386829D01*
G01X1562329Y466829D02*
X1565500Y470000D01*
G01D02*
X1568671Y473171D01*
G01X1562329D02*
X1565500Y470000D01*
G01D02*
X1568671Y466829D01*
G01X1562329Y546829D02*
X1565500Y550000D01*
G01D02*
X1568671Y553171D01*
G01X1562329D02*
X1565500Y550000D01*
G01D02*
X1568671Y546829D01*
G54D15*
X166785Y230000D03*
Y310000D03*
Y390000D03*
Y470000D03*
Y550000D03*
X243785Y230000D03*
Y310000D03*
Y390000D03*
Y470000D03*
Y550000D03*
X1488500Y230000D03*
Y310000D03*
Y390000D03*
Y470000D03*
Y550000D03*
X1565500Y230000D03*
Y310000D03*
Y390000D03*
Y470000D03*
Y550000D03*
G54D25*
G01X284646Y8012D02*
X289845D01*
X293106Y11273D01*
X293322Y11794D01*
Y14000D01*
X297322Y18000D01*
X312000D01*
X324000Y6000D01*
X1457986D01*
X1463274Y11288D01*
G01X1468873Y9127D02*
X1469988Y8012D01*
X1475197D01*
G01X551430Y132400D02*
X560120D01*
X563007Y129513D01*
Y118477D01*
G01X551430Y265600D02*
X554893D01*
X563007Y257486D01*
Y251677D01*
G01X574230Y132400D02*
X567441D01*
X565539Y130498D01*
Y116655D01*
X563007Y114123D01*
G01X576467Y265600D02*
X573547D01*
X565307Y257360D01*
Y252913D01*
X565507Y252713D01*
Y249823D01*
X563007Y247323D01*
G01X562830Y270000D02*
X563445Y269385D01*
X570612D01*
X575348Y274121D01*
X583795D01*
X591028Y266888D01*
Y255131D01*
X620300Y225859D01*
X654839D01*
X671567Y242587D01*
X700280D01*
X707422Y249729D01*
Y260662D01*
X706984Y261100D01*
G01X562830Y266500D02*
X563415Y267085D01*
X571565D01*
X576301Y271821D01*
X582842D01*
X588728Y265935D01*
Y254178D01*
X619347Y223559D01*
X655792D01*
X672520Y240287D01*
X701233D01*
X709722Y248776D01*
Y260738D01*
X710084Y261100D01*
G01X590298Y282890D02*
X588467Y281059D01*
X585702D01*
X584160Y282601D01*
X576046D01*
X569587Y276142D01*
X563688D01*
X562830Y277000D01*
G01X590298Y276984D02*
X588523Y278759D01*
X584749D01*
X583207Y280301D01*
X576999D01*
X570540Y273842D01*
X563172D01*
X562830Y273500D01*
G01X639010Y236377D02*
X636002Y239385D01*
Y274286D01*
X619593Y290695D01*
X615229D01*
X608259Y297665D01*
Y305000D01*
G01X632186Y338917D02*
X623500Y347603D01*
Y379000D01*
G01X978600Y310955D02*
X1014825D01*
X1039607Y286173D01*
Y279233D01*
X1038288Y277914D01*
Y263364D01*
X1047691Y253961D01*
X1098700D01*
X1100500Y255761D01*
Y263500D01*
G01X1199100Y277000D02*
X1198585Y276485D01*
X1194403D01*
X1192333Y278555D01*
Y319347D01*
X1178035Y333645D01*
X1110298D01*
X1076157Y299504D01*
X1058634D01*
X1052530Y293400D01*
Y291230D01*
X1052200Y290900D01*
G01X1199100Y273500D02*
X1198415Y274185D01*
X1193449D01*
X1190033Y277601D01*
Y318393D01*
X1177081Y331345D01*
X1111252D01*
X1077111Y297204D01*
X1059588D01*
X1055079Y292695D01*
Y291121D01*
X1055300Y290900D01*
G01X1087100Y282500D02*
X1094100Y289500D01*
X1101600D01*
G01X1140100Y244000D02*
X1124600Y259500D01*
Y271425D01*
G01X1154025Y247000D02*
X1154600Y247575D01*
Y253764D01*
X1160100Y259264D01*
Y279000D01*
X1163900Y282800D01*
Y311800D01*
X1158800Y316900D01*
X1137600D01*
X1135000Y319500D01*
X1123100D01*
G01X1187700Y132400D02*
X1196054D01*
X1199277Y129177D01*
Y118477D01*
G01X1187700Y265600D02*
X1188533Y264767D01*
X1197049D01*
X1199277Y262539D01*
Y251677D01*
G01X1199100Y270000D02*
X1198480Y269380D01*
X1193202D01*
X1189304Y273278D01*
X1173724D01*
X1171986Y275016D01*
G01Y269110D02*
X1173854Y270978D01*
X1188350D01*
X1192248Y267080D01*
X1198520D01*
X1199100Y266500D01*
G01X1210500Y132400D02*
X1203755D01*
X1201777Y130422D01*
Y116623D01*
X1199277Y114123D01*
G01X1210500Y265600D02*
X1203628D01*
X1201549Y263521D01*
X1201577Y263492D01*
Y252913D01*
X1201777Y252713D01*
Y249823D01*
X1199277Y247323D01*
G54D16*
X681498Y575042D03*
Y565042D03*
G54D26*
G01X-457143Y-1211429D02*
Y2242857D01*
X4308572D01*
Y-1211429D01*
X-457143D01*
G01X37000Y-995000D02*
Y-1070000D01*
X537000D01*
Y-995000D01*
X37000D01*
G01X49000Y-1060000D02*
Y-1065000D01*
G01X47543Y-1060000D02*
X50457D01*
G01X55367Y-1065000D02*
X52833D01*
Y-1060000D01*
X55367D01*
G01X54353Y-1062417D02*
X52833D01*
G01X57933Y-1060000D02*
Y-1065000D01*
X60467D01*
G01X64300Y-1065167D02*
X64173Y-1065083D01*
Y-1064917D01*
X64300Y-1064833D01*
X64427Y-1064917D01*
Y-1065083D01*
X64300Y-1065167D01*
G01Y-1062917D02*
X64173Y-1062833D01*
Y-1062667D01*
X64300Y-1062583D01*
X64427Y-1062667D01*
Y-1062833D01*
X64300Y-1062917D01*
G01X69083Y-1066667D02*
X68450Y-1065833D01*
X68133Y-1065000D01*
Y-1061667D01*
X68450Y-1060833D01*
X69083Y-1060000D01*
G01X74500D02*
X73993Y-1060167D01*
X73613Y-1060583D01*
X73360Y-1061083D01*
X73170Y-1061750D01*
X73107Y-1062500D01*
X73170Y-1063250D01*
X73360Y-1063917D01*
X73613Y-1064417D01*
X73993Y-1064833D01*
X74500Y-1065000D01*
X75007Y-1064833D01*
X75387Y-1064417D01*
X75640Y-1063917D01*
X75830Y-1063250D01*
X75893Y-1062500D01*
X75830Y-1061750D01*
X75640Y-1061083D01*
X75387Y-1060583D01*
X75007Y-1060167D01*
X74500Y-1060000D01*
G01X78207Y-1064000D02*
X78587Y-1064583D01*
X79093Y-1064917D01*
X79663Y-1065000D01*
X80170Y-1064917D01*
X80677Y-1064500D01*
X80993Y-1064000D01*
X81057Y-1063500D01*
X80930Y-1062917D01*
X80487Y-1062500D01*
X80043Y-1062333D01*
X79473D01*
G01X80043D02*
X80423Y-1062083D01*
X80740Y-1061667D01*
X80867Y-1061167D01*
X80740Y-1060667D01*
X80423Y-1060250D01*
X79853Y-1060000D01*
X79283Y-1060083D01*
X78713Y-1060417D01*
G01X85017Y-1066667D02*
X85650Y-1065833D01*
X85967Y-1065000D01*
Y-1061667D01*
X85650Y-1060833D01*
X85017Y-1060000D01*
G01X88407Y-1064000D02*
X88787Y-1064583D01*
X89293Y-1064917D01*
X89863Y-1065000D01*
X90370Y-1064917D01*
X90877Y-1064500D01*
X91193Y-1064000D01*
X91257Y-1063500D01*
X91130Y-1062917D01*
X90687Y-1062500D01*
X90243Y-1062333D01*
X89673D01*
G01X90243D02*
X90623Y-1062083D01*
X90940Y-1061667D01*
X91067Y-1061167D01*
X90940Y-1060667D01*
X90623Y-1060250D01*
X90053Y-1060000D01*
X89483Y-1060083D01*
X88913Y-1060417D01*
G01X93697Y-1060833D02*
X94077Y-1060333D01*
X94520Y-1060083D01*
X95027Y-1060000D01*
X95660Y-1060167D01*
X96103Y-1060583D01*
X96230Y-1061083D01*
X96167Y-1061583D01*
X95913Y-1062000D01*
X94647Y-1062833D01*
X94077Y-1063417D01*
X93697Y-1064250D01*
X93570Y-1065000D01*
X96230D01*
G01X99873D02*
X100000Y-1063917D01*
X100190Y-1063000D01*
X100443Y-1062167D01*
X100760Y-1061250D01*
X101267Y-1060000D01*
X98733D01*
G01X104277Y-1063333D02*
X105923D01*
G01X108997Y-1060833D02*
X109377Y-1060333D01*
X109820Y-1060083D01*
X110327Y-1060000D01*
X110960Y-1060167D01*
X111403Y-1060583D01*
X111530Y-1061083D01*
X111467Y-1061583D01*
X111213Y-1062000D01*
X109947Y-1062833D01*
X109377Y-1063417D01*
X108997Y-1064250D01*
X108870Y-1065000D01*
X111530D01*
G01X113907Y-1064000D02*
X114287Y-1064583D01*
X114793Y-1064917D01*
X115363Y-1065000D01*
X115870Y-1064917D01*
X116377Y-1064500D01*
X116693Y-1064000D01*
X116757Y-1063500D01*
X116630Y-1062917D01*
X116187Y-1062500D01*
X115743Y-1062333D01*
X115173D01*
G01X115743D02*
X116123Y-1062083D01*
X116440Y-1061667D01*
X116567Y-1061167D01*
X116440Y-1060667D01*
X116123Y-1060250D01*
X115553Y-1060000D01*
X114983Y-1060083D01*
X114413Y-1060417D01*
G01X121160Y-1065000D02*
Y-1060000D01*
X118817Y-1063583D01*
X121983D01*
G01X124107Y-1064250D02*
X124487Y-1064667D01*
X124930Y-1064917D01*
X125500Y-1065000D01*
X126070Y-1064833D01*
X126513Y-1064500D01*
X126830Y-1063917D01*
X126893Y-1063250D01*
X126767Y-1062583D01*
X126450Y-1062167D01*
X126007Y-1061833D01*
X125563Y-1061750D01*
X125120Y-1061833D01*
X124550Y-1062167D01*
X124740Y-1060000D01*
X126450D01*
G01X134497Y-1065000D02*
Y-1060000D01*
X136903D01*
G01X136017Y-1062417D02*
X134497D01*
G01X139217Y-1065000D02*
X140800Y-1060000D01*
X142383Y-1065000D01*
G01X141813Y-1063250D02*
X139787D01*
G01X144570Y-1065000D02*
X147230Y-1060000D01*
G01X144570D02*
X147230Y-1065000D01*
G01X151000Y-1065167D02*
X150873Y-1065083D01*
Y-1064917D01*
X151000Y-1064833D01*
X151127Y-1064917D01*
Y-1065083D01*
X151000Y-1065167D01*
G01Y-1062917D02*
X150873Y-1062833D01*
Y-1062667D01*
X151000Y-1062583D01*
X151127Y-1062667D01*
Y-1062833D01*
X151000Y-1062917D01*
G01X155783Y-1066667D02*
X155150Y-1065833D01*
X154833Y-1065000D01*
Y-1061667D01*
X155150Y-1060833D01*
X155783Y-1060000D01*
G01X161200D02*
X160693Y-1060167D01*
X160313Y-1060583D01*
X160060Y-1061083D01*
X159870Y-1061750D01*
X159807Y-1062500D01*
X159870Y-1063250D01*
X160060Y-1063917D01*
X160313Y-1064417D01*
X160693Y-1064833D01*
X161200Y-1065000D01*
X161707Y-1064833D01*
X162087Y-1064417D01*
X162340Y-1063917D01*
X162530Y-1063250D01*
X162593Y-1062500D01*
X162530Y-1061750D01*
X162340Y-1061083D01*
X162087Y-1060583D01*
X161707Y-1060167D01*
X161200Y-1060000D01*
G01X164907Y-1064000D02*
X165287Y-1064583D01*
X165793Y-1064917D01*
X166363Y-1065000D01*
X166870Y-1064917D01*
X167377Y-1064500D01*
X167693Y-1064000D01*
X167757Y-1063500D01*
X167630Y-1062917D01*
X167187Y-1062500D01*
X166743Y-1062333D01*
X166173D01*
G01X166743D02*
X167123Y-1062083D01*
X167440Y-1061667D01*
X167567Y-1061167D01*
X167440Y-1060667D01*
X167123Y-1060250D01*
X166553Y-1060000D01*
X165983Y-1060083D01*
X165413Y-1060417D01*
G01X171717Y-1066667D02*
X172350Y-1065833D01*
X172667Y-1065000D01*
Y-1061667D01*
X172350Y-1060833D01*
X171717Y-1060000D01*
G01X175107Y-1064000D02*
X175487Y-1064583D01*
X175993Y-1064917D01*
X176563Y-1065000D01*
X177070Y-1064917D01*
X177577Y-1064500D01*
X177893Y-1064000D01*
X177957Y-1063500D01*
X177830Y-1062917D01*
X177387Y-1062500D01*
X176943Y-1062333D01*
X176373D01*
G01X176943D02*
X177323Y-1062083D01*
X177640Y-1061667D01*
X177767Y-1061167D01*
X177640Y-1060667D01*
X177323Y-1060250D01*
X176753Y-1060000D01*
X176183Y-1060083D01*
X175613Y-1060417D01*
G01X180523Y-1064417D02*
X180967Y-1064833D01*
X181473Y-1065000D01*
X181980Y-1064833D01*
X182423Y-1064333D01*
X182740Y-1063583D01*
X182867Y-1062833D01*
Y-1061917D01*
X182740Y-1061167D01*
X182423Y-1060500D01*
X182043Y-1060167D01*
X181600Y-1060000D01*
X181093Y-1060167D01*
X180713Y-1060500D01*
X180460Y-1061000D01*
X180333Y-1061667D01*
X180460Y-1062250D01*
X180777Y-1062833D01*
X181157Y-1063167D01*
X181600Y-1063250D01*
X182107Y-1063083D01*
X182487Y-1062667D01*
X182867Y-1061917D01*
G01X186573Y-1065000D02*
X186700Y-1063917D01*
X186890Y-1063000D01*
X187143Y-1062167D01*
X187460Y-1061250D01*
X187967Y-1060000D01*
X185433D01*
G01X190977Y-1063333D02*
X192623D01*
G01X195507Y-1064000D02*
X195887Y-1064583D01*
X196393Y-1064917D01*
X196963Y-1065000D01*
X197470Y-1064917D01*
X197977Y-1064500D01*
X198293Y-1064000D01*
X198357Y-1063500D01*
X198230Y-1062917D01*
X197787Y-1062500D01*
X197343Y-1062333D01*
X196773D01*
G01X197343D02*
X197723Y-1062083D01*
X198040Y-1061667D01*
X198167Y-1061167D01*
X198040Y-1060667D01*
X197723Y-1060250D01*
X197153Y-1060000D01*
X196583Y-1060083D01*
X196013Y-1060417D01*
G01X200797Y-1062917D02*
X201240Y-1062333D01*
X201620Y-1062000D01*
X202127Y-1061833D01*
X202570Y-1062000D01*
X202887Y-1062333D01*
X203140Y-1062833D01*
X203203Y-1063417D01*
X203140Y-1063917D01*
X202887Y-1064417D01*
X202507Y-1064833D01*
X202063Y-1065000D01*
X201557Y-1064833D01*
X201113Y-1064333D01*
X200860Y-1063583D01*
X200797Y-1062750D01*
X200923Y-1061667D01*
X201113Y-1061083D01*
X201430Y-1060500D01*
X201873Y-1060083D01*
X202317Y-1060000D01*
X202760Y-1060167D01*
X203077Y-1060583D01*
G01X207100Y-1065000D02*
Y-1060000D01*
X206340Y-1061000D01*
G01Y-1065000D02*
X207860D01*
G01X212960D02*
Y-1060000D01*
X210617Y-1063583D01*
X213783D01*
G01X232000Y-995000D02*
Y-1070000D01*
G01Y-1045000D02*
X335000D01*
Y-1020000D01*
G01X232000D02*
X335000D01*
G01X337000Y-995000D02*
Y-1070000D01*
G01X335000Y-995000D02*
Y-1070000D01*
G01X342507Y-1055000D02*
Y-1050000D01*
X343773D01*
X344280Y-1050250D01*
X344660Y-1050583D01*
X344977Y-1051083D01*
X345230Y-1051667D01*
X345293Y-1052500D01*
X345230Y-1053333D01*
X344977Y-1053917D01*
X344660Y-1054417D01*
X344280Y-1054750D01*
X343773Y-1055000D01*
X342507D01*
G01X347417D02*
X349000Y-1050000D01*
X350583Y-1055000D01*
G01X350013Y-1053250D02*
X347987D01*
G01X354100Y-1050000D02*
Y-1055000D01*
G01X352643Y-1050000D02*
X355557D01*
G01X360467Y-1055000D02*
X357933D01*
Y-1050000D01*
X360467D01*
G01X359453Y-1052417D02*
X357933D01*
G01X364300Y-1055167D02*
X364173Y-1055083D01*
Y-1054917D01*
X364300Y-1054833D01*
X364427Y-1054917D01*
Y-1055083D01*
X364300Y-1055167D01*
G01Y-1052917D02*
X364173Y-1052833D01*
Y-1052667D01*
X364300Y-1052583D01*
X364427Y-1052667D01*
Y-1052833D01*
X364300Y-1052917D01*
G01X337000Y-1045000D02*
X537000D01*
G01X342633Y-1030000D02*
Y-1025000D01*
X344153D01*
X344660Y-1025250D01*
X345040Y-1025833D01*
X345167Y-1026500D01*
X345040Y-1027167D01*
X344723Y-1027667D01*
X344153Y-1027917D01*
X342633D01*
G01X347860Y-1030167D02*
X350140Y-1025000D01*
G01X352643Y-1030000D02*
Y-1025000D01*
X355557Y-1030000D01*
Y-1025000D01*
G01X359200Y-1030167D02*
X359073Y-1030083D01*
Y-1029917D01*
X359200Y-1029833D01*
X359327Y-1029917D01*
Y-1030083D01*
X359200Y-1030167D01*
G01Y-1027917D02*
X359073Y-1027833D01*
Y-1027667D01*
X359200Y-1027583D01*
X359327Y-1027667D01*
Y-1027833D01*
X359200Y-1027917D01*
G01X342633Y-1005000D02*
Y-1000000D01*
X344153D01*
X344660Y-1000250D01*
X345040Y-1000833D01*
X345167Y-1001500D01*
X345040Y-1002167D01*
X344723Y-1002667D01*
X344153Y-1002917D01*
X342633D01*
G01X347733Y-1005000D02*
Y-1000000D01*
X349317D01*
X349823Y-1000250D01*
X350140Y-1000583D01*
X350267Y-1001250D01*
X350140Y-1001917D01*
X349760Y-1002333D01*
X349317Y-1002583D01*
X347733D01*
G01X349317D02*
X350267Y-1005000D01*
G01X354100D02*
X353593Y-1004917D01*
X353150Y-1004583D01*
X352770Y-1004083D01*
X352517Y-1003500D01*
X352390Y-1002833D01*
Y-1002167D01*
X352517Y-1001500D01*
X352770Y-1000917D01*
X353150Y-1000417D01*
X353593Y-1000083D01*
X354100Y-1000000D01*
X354607Y-1000083D01*
X355050Y-1000417D01*
X355430Y-1000917D01*
X355683Y-1001500D01*
X355810Y-1002167D01*
Y-1002833D01*
X355683Y-1003500D01*
X355430Y-1004083D01*
X355050Y-1004583D01*
X354607Y-1004917D01*
X354100Y-1005000D01*
G01X357933Y-1004000D02*
X358250Y-1004500D01*
X358630Y-1004833D01*
X359073Y-1005000D01*
X359580Y-1004833D01*
X359960Y-1004500D01*
X360340Y-1004000D01*
X360467Y-1003333D01*
Y-1000000D01*
G01X365567Y-1005000D02*
X363033D01*
Y-1000000D01*
X365567D01*
G01X364553Y-1002417D02*
X363033D01*
G01X370793Y-1000417D02*
X370413Y-1000167D01*
X369970Y-1000000D01*
X369463D01*
X368893Y-1000250D01*
X368450Y-1000667D01*
X368133Y-1001167D01*
X367880Y-1002000D01*
X367817Y-1002750D01*
X367943Y-1003500D01*
X368133Y-1004000D01*
X368513Y-1004500D01*
X368957Y-1004833D01*
X369400Y-1005000D01*
X369843D01*
X370287Y-1004833D01*
X370667Y-1004583D01*
X370983Y-1004250D01*
G01X374500Y-1000000D02*
Y-1005000D01*
G01X373043Y-1000000D02*
X375957D01*
G01X379600Y-1005167D02*
X379473Y-1005083D01*
Y-1004917D01*
X379600Y-1004833D01*
X379727Y-1004917D01*
Y-1005083D01*
X379600Y-1005167D01*
G01Y-1002917D02*
X379473Y-1002833D01*
Y-1002667D01*
X379600Y-1002583D01*
X379727Y-1002667D01*
Y-1002833D01*
X379600Y-1002917D01*
G01X337000Y-1020000D02*
X537000D01*
G01X452000Y-1045000D02*
Y-1070000D01*
G01X454633Y-1047500D02*
Y-1052500D01*
X457167D01*
G01X460240Y-1047500D02*
X461760D01*
G01X461000D02*
Y-1052500D01*
G01X460240D02*
X461760D01*
G01X466607Y-1049833D02*
X466860Y-1049583D01*
X467050Y-1049167D01*
X467177Y-1048583D01*
X467050Y-1048083D01*
X466797Y-1047750D01*
X466353Y-1047500D01*
X464643D01*
Y-1052500D01*
X466733D01*
X467177Y-1052167D01*
X467430Y-1051667D01*
X467557Y-1051083D01*
X467430Y-1050500D01*
X467050Y-1050000D01*
X466607Y-1049833D01*
X464643D01*
G01X471200Y-1052667D02*
X471073Y-1052583D01*
Y-1052417D01*
X471200Y-1052333D01*
X471327Y-1052417D01*
Y-1052583D01*
X471200Y-1052667D01*
G01Y-1050417D02*
X471073Y-1050333D01*
Y-1050167D01*
X471200Y-1050083D01*
X471327Y-1050167D01*
Y-1050333D01*
X471200Y-1050417D01*
G01X495000Y-1045000D02*
Y-1070000D01*
G01X498900Y-1047500D02*
Y-1052500D01*
G01X497443Y-1047500D02*
X500357D01*
G01X504000Y-1052500D02*
X503620Y-1052417D01*
X503240Y-1052083D01*
X502987Y-1051500D01*
X502860Y-1050833D01*
X502987Y-1050167D01*
X503240Y-1049583D01*
X503620Y-1049250D01*
X504000Y-1049167D01*
X504380Y-1049250D01*
X504760Y-1049583D01*
X505013Y-1050167D01*
X505077Y-1050833D01*
X505013Y-1051500D01*
X504760Y-1052083D01*
X504380Y-1052417D01*
X504000Y-1052500D01*
G01X509100D02*
X508720Y-1052417D01*
X508340Y-1052083D01*
X508087Y-1051500D01*
X507960Y-1050833D01*
X508087Y-1050167D01*
X508340Y-1049583D01*
X508720Y-1049250D01*
X509100Y-1049167D01*
X509480Y-1049250D01*
X509860Y-1049583D01*
X510113Y-1050167D01*
X510177Y-1050833D01*
X510113Y-1051500D01*
X509860Y-1052083D01*
X509480Y-1052417D01*
X509100Y-1052500D01*
G01X514200D02*
Y-1047500D01*
G01X519300Y-1052667D02*
X519173Y-1052583D01*
Y-1052417D01*
X519300Y-1052333D01*
X519427Y-1052417D01*
Y-1052583D01*
X519300Y-1052667D01*
G01Y-1050417D02*
X519173Y-1050333D01*
Y-1050167D01*
X519300Y-1050083D01*
X519427Y-1050167D01*
Y-1050333D01*
X519300Y-1050417D01*
G01X495000Y-1020000D02*
Y-1045000D01*
G01X497633Y-1027500D02*
Y-1022500D01*
X499217D01*
X499723Y-1022750D01*
X500040Y-1023083D01*
X500167Y-1023750D01*
X500040Y-1024417D01*
X499660Y-1024833D01*
X499217Y-1025083D01*
X497633D01*
G01X499217D02*
X500167Y-1027500D01*
G01X505267D02*
X502733D01*
Y-1022500D01*
X505267D01*
G01X504253Y-1024917D02*
X502733D01*
G01X507517Y-1022500D02*
X509100Y-1027500D01*
X510683Y-1022500D01*
G01X514200Y-1027667D02*
X514073Y-1027583D01*
Y-1027417D01*
X514200Y-1027333D01*
X514327Y-1027417D01*
Y-1027583D01*
X514200Y-1027667D01*
G01Y-1025417D02*
X514073Y-1025333D01*
Y-1025167D01*
X514200Y-1025083D01*
X514327Y-1025167D01*
Y-1025333D01*
X514200Y-1025417D01*
G01X503013Y-1073167D02*
X503120Y-1073042D01*
X503200Y-1072833D01*
X503253Y-1072542D01*
X503200Y-1072292D01*
X503093Y-1072125D01*
X502907Y-1072000D01*
X502187D01*
Y-1074500D01*
X503067D01*
X503253Y-1074333D01*
X503360Y-1074083D01*
X503413Y-1073792D01*
X503360Y-1073500D01*
X503200Y-1073250D01*
X503013Y-1073167D01*
X502187D01*
G01X505480Y-1074500D02*
Y-1072833D01*
G01Y-1073125D02*
X505373Y-1072958D01*
X505213Y-1072875D01*
X505027Y-1072833D01*
X504840Y-1072917D01*
X504680Y-1073083D01*
X504573Y-1073333D01*
X504520Y-1073667D01*
X504573Y-1074000D01*
X504680Y-1074250D01*
X504840Y-1074417D01*
X505027Y-1074500D01*
X505213Y-1074458D01*
X505373Y-1074333D01*
X505480Y-1074167D01*
G01X506800Y-1074208D02*
X506933Y-1074375D01*
X507120Y-1074500D01*
X507280D01*
X507440Y-1074417D01*
X507547Y-1074292D01*
X507600Y-1074125D01*
X507573Y-1073875D01*
X507467Y-1073750D01*
X506987Y-1073500D01*
X506880Y-1073208D01*
X506933Y-1073000D01*
X507040Y-1072875D01*
X507200Y-1072833D01*
X507360Y-1072875D01*
X507520Y-1073000D01*
G01X509000Y-1073375D02*
X509853D01*
X509773Y-1073083D01*
X509640Y-1072917D01*
X509453Y-1072833D01*
X509267Y-1072875D01*
X509107Y-1073000D01*
X509000Y-1073292D01*
X508947Y-1073542D01*
Y-1073792D01*
X509000Y-1074042D01*
X509133Y-1074292D01*
X509293Y-1074458D01*
X509480Y-1074500D01*
X509667Y-1074417D01*
X509853Y-1074167D01*
G01X511120Y-1074500D02*
Y-1072000D01*
G01Y-1073250D02*
X511253Y-1073000D01*
X511413Y-1072875D01*
X511573Y-1072833D01*
X511813Y-1072917D01*
X511973Y-1073083D01*
X512080Y-1073375D01*
Y-1073708D01*
X512027Y-1074042D01*
X511920Y-1074292D01*
X511733Y-1074458D01*
X511573Y-1074500D01*
X511413Y-1074458D01*
X511253Y-1074333D01*
X511120Y-1074125D01*
G01X513800Y-1074500D02*
X513640Y-1074458D01*
X513480Y-1074292D01*
X513373Y-1074000D01*
X513320Y-1073667D01*
X513373Y-1073333D01*
X513480Y-1073042D01*
X513640Y-1072875D01*
X513800Y-1072833D01*
X513960Y-1072875D01*
X514120Y-1073042D01*
X514227Y-1073333D01*
X514253Y-1073667D01*
X514227Y-1074000D01*
X514120Y-1074292D01*
X513960Y-1074458D01*
X513800Y-1074500D01*
G01X516480D02*
Y-1072833D01*
G01Y-1073125D02*
X516373Y-1072958D01*
X516213Y-1072875D01*
X516027Y-1072833D01*
X515840Y-1072917D01*
X515680Y-1073083D01*
X515573Y-1073333D01*
X515520Y-1073667D01*
X515573Y-1074000D01*
X515680Y-1074250D01*
X515840Y-1074417D01*
X516027Y-1074500D01*
X516213Y-1074458D01*
X516373Y-1074333D01*
X516480Y-1074167D01*
G01X517827Y-1074500D02*
Y-1072833D01*
G01Y-1073167D02*
X517960Y-1073000D01*
X518093Y-1072875D01*
X518280Y-1072833D01*
X518413Y-1072875D01*
X518573Y-1073000D01*
G01X520880Y-1072000D02*
Y-1074500D01*
G01Y-1074125D02*
X520773Y-1074333D01*
X520613Y-1074458D01*
X520427Y-1074500D01*
X520213Y-1074417D01*
X520053Y-1074208D01*
X519947Y-1073958D01*
X519920Y-1073667D01*
X519947Y-1073375D01*
X520053Y-1073125D01*
X520213Y-1072917D01*
X520427Y-1072833D01*
X520613Y-1072875D01*
X520747Y-1072958D01*
X520880Y-1073125D01*
G01X524267Y-1074500D02*
Y-1072000D01*
X524933D01*
X525147Y-1072125D01*
X525280Y-1072292D01*
X525333Y-1072625D01*
X525280Y-1072958D01*
X525120Y-1073167D01*
X524933Y-1073292D01*
X524267D01*
G01X524933D02*
X525333Y-1074500D01*
G01X526600Y-1073375D02*
X527453D01*
X527373Y-1073083D01*
X527240Y-1072917D01*
X527053Y-1072833D01*
X526867Y-1072875D01*
X526707Y-1073000D01*
X526600Y-1073292D01*
X526547Y-1073542D01*
Y-1073792D01*
X526600Y-1074042D01*
X526733Y-1074292D01*
X526893Y-1074458D01*
X527080Y-1074500D01*
X527267Y-1074417D01*
X527453Y-1074167D01*
G01X528720Y-1072833D02*
X529200Y-1074500D01*
X529680Y-1072833D01*
G01X531400Y-1074583D02*
X531347Y-1074542D01*
Y-1074458D01*
X531400Y-1074417D01*
X531453Y-1074458D01*
Y-1074542D01*
X531400Y-1074583D01*
G01X533600Y-1074500D02*
X533787Y-1074458D01*
X534000Y-1074333D01*
X534133Y-1074125D01*
X534187Y-1073833D01*
X534133Y-1073542D01*
X533973Y-1073292D01*
X533733Y-1073167D01*
X533467D01*
X533307Y-1073083D01*
X533173Y-1072875D01*
X533120Y-1072583D01*
X533200Y-1072292D01*
X533387Y-1072083D01*
X533600Y-1072000D01*
X533813Y-1072083D01*
X534000Y-1072292D01*
X534080Y-1072583D01*
X534027Y-1072875D01*
X533893Y-1073083D01*
X533733Y-1073167D01*
X533467D01*
X533227Y-1073292D01*
X533067Y-1073542D01*
X533013Y-1073833D01*
X533067Y-1074125D01*
X533200Y-1074333D01*
X533413Y-1074458D01*
X533600Y-1074500D01*
G01X536013Y-1073167D02*
X536120Y-1073042D01*
X536200Y-1072833D01*
X536253Y-1072542D01*
X536200Y-1072292D01*
X536093Y-1072125D01*
X535907Y-1072000D01*
X535187D01*
Y-1074500D01*
X536067D01*
X536253Y-1074333D01*
X536360Y-1074083D01*
X536413Y-1073792D01*
X536360Y-1073500D01*
X536200Y-1073250D01*
X536013Y-1073167D01*
X535187D01*
G01X-457143Y-1211429D02*
Y2242857D01*
X4308572D01*
Y-1211429D01*
X-457143D01*
G01X71650Y-1024800D02*
X69130Y-1024383D01*
X66925Y-1022717D01*
X65035Y-1020217D01*
X63775Y-1017300D01*
X63145Y-1013967D01*
Y-1010633D01*
X63775Y-1007300D01*
X65035Y-1004383D01*
X66925Y-1001884D01*
X69130Y-1000217D01*
X71650Y-999800D01*
X74170Y-1000217D01*
X76375Y-1001884D01*
X78265Y-1004383D01*
X79525Y-1007300D01*
X80155Y-1010633D01*
Y-1013967D01*
X79525Y-1017300D01*
X78265Y-1020217D01*
X76375Y-1022717D01*
X74170Y-1024383D01*
X71650Y-1024800D01*
G01X74170Y-1018133D02*
X77950Y-1024800D01*
G01X91495Y-1008134D02*
Y-1019800D01*
X92755Y-1022717D01*
X94645Y-1024383D01*
X96850Y-1024800D01*
X99055Y-1024383D01*
X100945Y-1022717D01*
X102205Y-1019800D01*
G01Y-1024800D02*
Y-1008134D01*
G01X127720Y-1024800D02*
Y-1008134D01*
G01Y-1011050D02*
X126460Y-1009384D01*
X124570Y-1008550D01*
X122365Y-1008134D01*
X120160Y-1008967D01*
X118270Y-1010633D01*
X117010Y-1013134D01*
X116380Y-1016467D01*
X117010Y-1019800D01*
X118270Y-1022301D01*
X120160Y-1023967D01*
X122365Y-1024800D01*
X124570Y-1024383D01*
X126460Y-1023134D01*
X127720Y-1021467D01*
G01X141895Y-1024800D02*
Y-1008134D01*
G01Y-1012300D02*
X143155Y-1010217D01*
X145045Y-1008550D01*
X147565Y-1008134D01*
X149770Y-1008550D01*
X151660Y-1010217D01*
X152605Y-1013134D01*
Y-1024800D01*
G01X172450Y-999800D02*
Y-1024800D01*
G01X168040Y-1008134D02*
X176860D01*
G01X203320Y-1024800D02*
Y-1008134D01*
G01Y-1011050D02*
X202060Y-1009384D01*
X200170Y-1008550D01*
X197965Y-1008134D01*
X195760Y-1008967D01*
X193870Y-1010633D01*
X192610Y-1013134D01*
X191980Y-1016467D01*
X192610Y-1019800D01*
X193870Y-1022301D01*
X195760Y-1023967D01*
X197965Y-1024800D01*
X200170Y-1024383D01*
X202060Y-1023134D01*
X203320Y-1021467D01*
G01X49820Y-1042350D02*
X51387D01*
Y-1044240D01*
X50917Y-1044870D01*
X50368Y-1045290D01*
X49585Y-1045500D01*
X48802Y-1045290D01*
X48253Y-1044870D01*
X47783Y-1044240D01*
X47470Y-1043505D01*
X47313Y-1042665D01*
Y-1041930D01*
X47470Y-1041300D01*
X47783Y-1040565D01*
X48253Y-1039935D01*
X48723Y-1039515D01*
X49350Y-1039200D01*
X49898D01*
X50525Y-1039410D01*
X50995Y-1039830D01*
G01X53927Y-1039200D02*
Y-1043715D01*
X54240Y-1044660D01*
X54867Y-1045290D01*
X55650Y-1045500D01*
X56433Y-1045290D01*
X57060Y-1044660D01*
X57373Y-1043715D01*
Y-1039200D01*
G01X61010D02*
X62890D01*
G01X61950D02*
Y-1045500D01*
G01X61010D02*
X62890D01*
G01X66605Y-1044660D02*
X67232Y-1045185D01*
X67937Y-1045500D01*
X68563D01*
X69190Y-1045185D01*
X69660Y-1044660D01*
X69895Y-1043925D01*
X69738Y-1043190D01*
X69347Y-1042560D01*
X68642Y-1042140D01*
X67702Y-1041930D01*
X67153Y-1041510D01*
X66918Y-1040775D01*
X67075Y-1040040D01*
X67467Y-1039515D01*
X68015Y-1039200D01*
X68563D01*
X69112Y-1039410D01*
X69582Y-1039935D01*
G01X72905Y-1045500D02*
Y-1039200D01*
G01X76195D02*
Y-1045500D01*
G01Y-1042350D02*
X72905D01*
G01X78892Y-1045500D02*
X80850Y-1039200D01*
X82808Y-1045500D01*
G01X82103Y-1043295D02*
X79597D01*
G01X85348Y-1045500D02*
Y-1039200D01*
X88952Y-1045500D01*
Y-1039200D01*
G01X98027Y-1045500D02*
Y-1039200D01*
X99593D01*
X100220Y-1039515D01*
X100690Y-1039935D01*
X101082Y-1040565D01*
X101395Y-1041300D01*
X101473Y-1042350D01*
X101395Y-1043400D01*
X101082Y-1044135D01*
X100690Y-1044765D01*
X100220Y-1045185D01*
X99593Y-1045500D01*
X98027D01*
G01X105110Y-1039200D02*
X106990D01*
G01X106050D02*
Y-1045500D01*
G01X105110D02*
X106990D01*
G01X110705Y-1044660D02*
X111332Y-1045185D01*
X112037Y-1045500D01*
X112663D01*
X113290Y-1045185D01*
X113760Y-1044660D01*
X113995Y-1043925D01*
X113838Y-1043190D01*
X113447Y-1042560D01*
X112742Y-1042140D01*
X111802Y-1041930D01*
X111253Y-1041510D01*
X111018Y-1040775D01*
X111175Y-1040040D01*
X111567Y-1039515D01*
X112115Y-1039200D01*
X112663D01*
X113212Y-1039410D01*
X113682Y-1039935D01*
G01X118650Y-1039200D02*
Y-1045500D01*
G01X116848Y-1039200D02*
X120452D01*
G01X124950Y-1045710D02*
X124793Y-1045605D01*
Y-1045395D01*
X124950Y-1045290D01*
X125107Y-1045395D01*
Y-1045605D01*
X124950Y-1045710D01*
G01X131093Y-1046655D02*
X131407Y-1045290D01*
G01X137550Y-1039200D02*
Y-1045500D01*
G01X135748Y-1039200D02*
X139352D01*
G01X141892Y-1045500D02*
X143850Y-1039200D01*
X145808Y-1045500D01*
G01X145103Y-1043295D02*
X142597D01*
G01X150150Y-1045500D02*
X149523Y-1045395D01*
X148975Y-1044975D01*
X148505Y-1044345D01*
X148192Y-1043610D01*
X148035Y-1042770D01*
Y-1041930D01*
X148192Y-1041090D01*
X148505Y-1040355D01*
X148975Y-1039725D01*
X149523Y-1039305D01*
X150150Y-1039200D01*
X150777Y-1039305D01*
X151325Y-1039725D01*
X151795Y-1040355D01*
X152108Y-1041090D01*
X152265Y-1041930D01*
Y-1042770D01*
X152108Y-1043610D01*
X151795Y-1044345D01*
X151325Y-1044975D01*
X150777Y-1045395D01*
X150150Y-1045500D01*
G01X156450D02*
Y-1042665D01*
X154883Y-1039200D01*
G01X158017D02*
X156450Y-1042665D01*
G01X161027Y-1039200D02*
Y-1043715D01*
X161340Y-1044660D01*
X161967Y-1045290D01*
X162750Y-1045500D01*
X163533Y-1045290D01*
X164160Y-1044660D01*
X164473Y-1043715D01*
Y-1039200D01*
G01X167092Y-1045500D02*
X169050Y-1039200D01*
X171008Y-1045500D01*
G01X170303Y-1043295D02*
X167797D01*
G01X173548Y-1045500D02*
Y-1039200D01*
X177152Y-1045500D01*
Y-1039200D01*
G01X51073Y-1049725D02*
X50603Y-1049410D01*
X50055Y-1049200D01*
X49428D01*
X48723Y-1049515D01*
X48175Y-1050040D01*
X47783Y-1050670D01*
X47470Y-1051720D01*
X47392Y-1052665D01*
X47548Y-1053610D01*
X47783Y-1054240D01*
X48253Y-1054870D01*
X48802Y-1055290D01*
X49350Y-1055500D01*
X49898D01*
X50447Y-1055290D01*
X50917Y-1054975D01*
X51308Y-1054555D01*
G01X54710Y-1049200D02*
X56590D01*
G01X55650D02*
Y-1055500D01*
G01X54710D02*
X56590D01*
G01X61950Y-1049200D02*
Y-1055500D01*
G01X60148Y-1049200D02*
X63752D01*
G01X68250Y-1055500D02*
Y-1052665D01*
X66683Y-1049200D01*
G01X69817D02*
X68250Y-1052665D01*
G01X79127Y-1054240D02*
X79597Y-1054975D01*
X80223Y-1055395D01*
X80928Y-1055500D01*
X81555Y-1055395D01*
X82182Y-1054870D01*
X82573Y-1054240D01*
X82652Y-1053610D01*
X82495Y-1052875D01*
X81947Y-1052350D01*
X81398Y-1052140D01*
X80693D01*
G01X81398D02*
X81868Y-1051825D01*
X82260Y-1051300D01*
X82417Y-1050670D01*
X82260Y-1050040D01*
X81868Y-1049515D01*
X81163Y-1049200D01*
X80458Y-1049305D01*
X79753Y-1049725D01*
G01X85427Y-1054240D02*
X85897Y-1054975D01*
X86523Y-1055395D01*
X87228Y-1055500D01*
X87855Y-1055395D01*
X88482Y-1054870D01*
X88873Y-1054240D01*
X88952Y-1053610D01*
X88795Y-1052875D01*
X88247Y-1052350D01*
X87698Y-1052140D01*
X86993D01*
G01X87698D02*
X88168Y-1051825D01*
X88560Y-1051300D01*
X88717Y-1050670D01*
X88560Y-1050040D01*
X88168Y-1049515D01*
X87463Y-1049200D01*
X86758Y-1049305D01*
X86053Y-1049725D01*
G01X91727Y-1054240D02*
X92197Y-1054975D01*
X92823Y-1055395D01*
X93528Y-1055500D01*
X94155Y-1055395D01*
X94782Y-1054870D01*
X95173Y-1054240D01*
X95252Y-1053610D01*
X95095Y-1052875D01*
X94547Y-1052350D01*
X93998Y-1052140D01*
X93293D01*
G01X93998D02*
X94468Y-1051825D01*
X94860Y-1051300D01*
X95017Y-1050670D01*
X94860Y-1050040D01*
X94468Y-1049515D01*
X93763Y-1049200D01*
X93058Y-1049305D01*
X92353Y-1049725D01*
G01X99593Y-1055500D02*
X99750Y-1054135D01*
X99985Y-1052980D01*
X100298Y-1051930D01*
X100690Y-1050775D01*
X101317Y-1049200D01*
X98183D01*
G01X105893Y-1055500D02*
X106050Y-1054135D01*
X106285Y-1052980D01*
X106598Y-1051930D01*
X106990Y-1050775D01*
X107617Y-1049200D01*
X104483D01*
G01X112193Y-1056655D02*
X112507Y-1055290D01*
G01X118650Y-1049200D02*
Y-1055500D01*
G01X116848Y-1049200D02*
X120452D01*
G01X122992Y-1055500D02*
X124950Y-1049200D01*
X126908Y-1055500D01*
G01X126203Y-1053295D02*
X123697D01*
G01X130310Y-1049200D02*
X132190D01*
G01X131250D02*
Y-1055500D01*
G01X130310D02*
X132190D01*
G01X135200Y-1049200D02*
X136297Y-1055500D01*
X137550Y-1049200D01*
X138803Y-1055500D01*
X139900Y-1049200D01*
G01X141892Y-1055500D02*
X143850Y-1049200D01*
X145808Y-1055500D01*
G01X145103Y-1053295D02*
X142597D01*
G01X148348Y-1055500D02*
Y-1049200D01*
X151952Y-1055500D01*
Y-1049200D01*
G01X162358Y-1057600D02*
X161575Y-1056550D01*
X161183Y-1055500D01*
Y-1051300D01*
X161575Y-1050250D01*
X162358Y-1049200D01*
G01X173783Y-1055500D02*
Y-1049200D01*
X175742D01*
X176368Y-1049515D01*
X176760Y-1049935D01*
X176917Y-1050775D01*
X176760Y-1051615D01*
X176290Y-1052140D01*
X175742Y-1052455D01*
X173783D01*
G01X175742D02*
X176917Y-1055500D01*
G01X181650Y-1055710D02*
X181493Y-1055605D01*
Y-1055395D01*
X181650Y-1055290D01*
X181807Y-1055395D01*
Y-1055605D01*
X181650Y-1055710D01*
G01X187950Y-1055500D02*
X187323Y-1055395D01*
X186775Y-1054975D01*
X186305Y-1054345D01*
X185992Y-1053610D01*
X185835Y-1052770D01*
Y-1051930D01*
X185992Y-1051090D01*
X186305Y-1050355D01*
X186775Y-1049725D01*
X187323Y-1049305D01*
X187950Y-1049200D01*
X188577Y-1049305D01*
X189125Y-1049725D01*
X189595Y-1050355D01*
X189908Y-1051090D01*
X190065Y-1051930D01*
Y-1052770D01*
X189908Y-1053610D01*
X189595Y-1054345D01*
X189125Y-1054975D01*
X188577Y-1055395D01*
X187950Y-1055500D01*
G01X194250Y-1055710D02*
X194093Y-1055605D01*
Y-1055395D01*
X194250Y-1055290D01*
X194407Y-1055395D01*
Y-1055605D01*
X194250Y-1055710D01*
G01X202273Y-1049725D02*
X201803Y-1049410D01*
X201255Y-1049200D01*
X200628D01*
X199923Y-1049515D01*
X199375Y-1050040D01*
X198983Y-1050670D01*
X198670Y-1051720D01*
X198592Y-1052665D01*
X198748Y-1053610D01*
X198983Y-1054240D01*
X199453Y-1054870D01*
X200002Y-1055290D01*
X200550Y-1055500D01*
X201098D01*
X201647Y-1055290D01*
X202117Y-1054975D01*
X202508Y-1054555D01*
G01X206850Y-1055710D02*
X206693Y-1055605D01*
Y-1055395D01*
X206850Y-1055290D01*
X207007Y-1055395D01*
Y-1055605D01*
X206850Y-1055710D01*
G01X213542Y-1057600D02*
X214325Y-1056550D01*
X214717Y-1055500D01*
Y-1051300D01*
X214325Y-1050250D01*
X213542Y-1049200D01*
G01X47548Y-1035500D02*
Y-1029200D01*
X51152Y-1035500D01*
Y-1029200D01*
G01X55650Y-1035500D02*
X55023Y-1035395D01*
X54475Y-1034975D01*
X54005Y-1034345D01*
X53692Y-1033610D01*
X53535Y-1032770D01*
Y-1031930D01*
X53692Y-1031090D01*
X54005Y-1030355D01*
X54475Y-1029725D01*
X55023Y-1029305D01*
X55650Y-1029200D01*
X56277Y-1029305D01*
X56825Y-1029725D01*
X57295Y-1030355D01*
X57608Y-1031090D01*
X57765Y-1031930D01*
Y-1032770D01*
X57608Y-1033610D01*
X57295Y-1034345D01*
X56825Y-1034975D01*
X56277Y-1035395D01*
X55650Y-1035500D01*
G01X61950Y-1035710D02*
X61793Y-1035605D01*
Y-1035395D01*
X61950Y-1035290D01*
X62107Y-1035395D01*
Y-1035605D01*
X61950Y-1035710D01*
G01X66762Y-1030250D02*
X67232Y-1029620D01*
X67780Y-1029305D01*
X68407Y-1029200D01*
X69190Y-1029410D01*
X69738Y-1029935D01*
X69895Y-1030565D01*
X69817Y-1031195D01*
X69503Y-1031720D01*
X67937Y-1032770D01*
X67232Y-1033505D01*
X66762Y-1034555D01*
X66605Y-1035500D01*
X69895D01*
G01X74550D02*
Y-1029200D01*
X73610Y-1030460D01*
G01Y-1035500D02*
X75490D01*
G01X80850D02*
Y-1029200D01*
X79910Y-1030460D01*
G01Y-1035500D02*
X81790D01*
G01X86993Y-1036655D02*
X87307Y-1035290D01*
G01X91100Y-1029200D02*
X92197Y-1035500D01*
X93450Y-1029200D01*
X94703Y-1035500D01*
X95800Y-1029200D01*
G01X101317Y-1035500D02*
X98183D01*
Y-1029200D01*
X101317D01*
G01X100063Y-1032245D02*
X98183D01*
G01X104248Y-1035500D02*
Y-1029200D01*
X107852Y-1035500D01*
Y-1029200D01*
G01X110705Y-1035500D02*
Y-1029200D01*
G01X113995D02*
Y-1035500D01*
G01Y-1032350D02*
X110705D01*
G01X116927Y-1029200D02*
Y-1033715D01*
X117240Y-1034660D01*
X117867Y-1035290D01*
X118650Y-1035500D01*
X119433Y-1035290D01*
X120060Y-1034660D01*
X120373Y-1033715D01*
Y-1029200D01*
G01X122992Y-1035500D02*
X124950Y-1029200D01*
X126908Y-1035500D01*
G01X126203Y-1033295D02*
X123697D01*
G01X136062Y-1030250D02*
X136532Y-1029620D01*
X137080Y-1029305D01*
X137707Y-1029200D01*
X138490Y-1029410D01*
X139038Y-1029935D01*
X139195Y-1030565D01*
X139117Y-1031195D01*
X138803Y-1031720D01*
X137237Y-1032770D01*
X136532Y-1033505D01*
X136062Y-1034555D01*
X135905Y-1035500D01*
X139195D01*
G01X142048D02*
Y-1029200D01*
X145652Y-1035500D01*
Y-1029200D01*
G01X148427Y-1035500D02*
Y-1029200D01*
X149993D01*
X150620Y-1029515D01*
X151090Y-1029935D01*
X151482Y-1030565D01*
X151795Y-1031300D01*
X151873Y-1032350D01*
X151795Y-1033400D01*
X151482Y-1034135D01*
X151090Y-1034765D01*
X150620Y-1035185D01*
X149993Y-1035500D01*
X148427D01*
G01X161183D02*
Y-1029200D01*
X163142D01*
X163768Y-1029515D01*
X164160Y-1029935D01*
X164317Y-1030775D01*
X164160Y-1031615D01*
X163690Y-1032140D01*
X163142Y-1032455D01*
X161183D01*
G01X163142D02*
X164317Y-1035500D01*
G01X167327D02*
Y-1029200D01*
X168893D01*
X169520Y-1029515D01*
X169990Y-1029935D01*
X170382Y-1030565D01*
X170695Y-1031300D01*
X170773Y-1032350D01*
X170695Y-1033400D01*
X170382Y-1034135D01*
X169990Y-1034765D01*
X169520Y-1035185D01*
X168893Y-1035500D01*
X167327D01*
G01X175350Y-1035710D02*
X175193Y-1035605D01*
Y-1035395D01*
X175350Y-1035290D01*
X175507Y-1035395D01*
Y-1035605D01*
X175350Y-1035710D01*
G01X243000Y-1004500D02*
Y-1012500D01*
X247000D01*
G01X254800D02*
Y-1007167D01*
G01Y-1008100D02*
X254400Y-1007567D01*
X253800Y-1007300D01*
X253100Y-1007167D01*
X252400Y-1007433D01*
X251800Y-1007967D01*
X251400Y-1008767D01*
X251200Y-1009833D01*
X251400Y-1010900D01*
X251800Y-1011700D01*
X252400Y-1012233D01*
X253100Y-1012500D01*
X253800Y-1012367D01*
X254400Y-1011967D01*
X254800Y-1011434D01*
G01X258900Y-1014900D02*
X259500Y-1015167D01*
X260300Y-1014900D01*
X260800Y-1014367D01*
X261200Y-1013700D01*
X261800Y-1011567D01*
X263100Y-1007167D01*
G01X259900D02*
X261800Y-1011567D01*
G01X267500Y-1008900D02*
X270700D01*
X270400Y-1007967D01*
X269900Y-1007433D01*
X269200Y-1007167D01*
X268500Y-1007300D01*
X267900Y-1007700D01*
X267500Y-1008633D01*
X267300Y-1009434D01*
Y-1010233D01*
X267500Y-1011033D01*
X268000Y-1011833D01*
X268600Y-1012367D01*
X269300Y-1012500D01*
X270000Y-1012233D01*
X270700Y-1011434D01*
G01X275600Y-1012500D02*
Y-1007167D01*
G01Y-1008233D02*
X276100Y-1007700D01*
X276600Y-1007300D01*
X277300Y-1007167D01*
X277800Y-1007300D01*
X278400Y-1007700D01*
G01X262100Y-1054500D02*
X265900D01*
X262100Y-1062500D01*
X265900D01*
G01X272000Y-1057167D02*
Y-1062500D01*
G01Y-1055033D02*
X271800Y-1054900D01*
Y-1054633D01*
X272000Y-1054500D01*
X272200Y-1054633D01*
Y-1054900D01*
X272000Y-1055033D01*
G01X278700Y-1059833D02*
X281300D01*
G01X286200Y-1065167D02*
Y-1057167D01*
G01Y-1058367D02*
X286700Y-1057700D01*
X287200Y-1057300D01*
X288000Y-1057167D01*
X288700Y-1057300D01*
X289400Y-1057967D01*
X289700Y-1058900D01*
X289800Y-1059833D01*
X289700Y-1060767D01*
X289400Y-1061700D01*
X288800Y-1062233D01*
X288000Y-1062500D01*
X287300Y-1062367D01*
X286600Y-1061967D01*
X286200Y-1061434D01*
G01X296000Y-1057167D02*
Y-1062500D01*
G01Y-1055033D02*
X295800Y-1054900D01*
Y-1054633D01*
X296000Y-1054500D01*
X296200Y-1054633D01*
Y-1054900D01*
X296000Y-1055033D01*
G01X302300Y-1062500D02*
Y-1057167D01*
G01Y-1058500D02*
X302700Y-1057833D01*
X303300Y-1057300D01*
X304100Y-1057167D01*
X304800Y-1057300D01*
X305400Y-1057833D01*
X305700Y-1058767D01*
Y-1062500D01*
G01X310600Y-1064500D02*
X311300Y-1065033D01*
X312100Y-1065167D01*
X312800Y-1065033D01*
X313400Y-1064367D01*
X313800Y-1063433D01*
Y-1057167D01*
G01Y-1058233D02*
X313400Y-1057700D01*
X312800Y-1057300D01*
X312100Y-1057167D01*
X311300Y-1057433D01*
X310800Y-1057967D01*
X310400Y-1058900D01*
X310200Y-1059833D01*
X310300Y-1060633D01*
X310700Y-1061567D01*
X311300Y-1062233D01*
X312100Y-1062500D01*
X312700Y-1062367D01*
X313400Y-1061833D01*
X313800Y-1061300D01*
G01X272800Y-1029500D02*
X275200D01*
G01X274000D02*
Y-1037500D01*
G01X272800D02*
X275200D01*
G01X279700D02*
Y-1029500D01*
X284300Y-1037500D01*
Y-1029500D01*
G01X290000Y-1037500D02*
Y-1029500D01*
X288800Y-1031100D01*
G01Y-1037500D02*
X291200D01*
G01X294300Y-1010900D02*
X294900Y-1011833D01*
X295700Y-1012367D01*
X296600Y-1012500D01*
X297400Y-1012367D01*
X298200Y-1011700D01*
X298700Y-1010900D01*
X298800Y-1010100D01*
X298600Y-1009167D01*
X297900Y-1008500D01*
X297200Y-1008233D01*
X296300D01*
G01X297200D02*
X297800Y-1007833D01*
X298300Y-1007167D01*
X298500Y-1006367D01*
X298300Y-1005567D01*
X297800Y-1004900D01*
X296900Y-1004500D01*
X296000Y-1004633D01*
X295100Y-1005167D01*
G01X369600Y-1055833D02*
X370200Y-1055033D01*
X370900Y-1054633D01*
X371700Y-1054500D01*
X372700Y-1054767D01*
X373400Y-1055433D01*
X373600Y-1056233D01*
X373500Y-1057034D01*
X373100Y-1057700D01*
X371100Y-1059033D01*
X370200Y-1059967D01*
X369600Y-1061300D01*
X369400Y-1062500D01*
X373600D01*
G01X379500Y-1054500D02*
X378700Y-1054767D01*
X378100Y-1055433D01*
X377700Y-1056233D01*
X377400Y-1057300D01*
X377300Y-1058500D01*
X377400Y-1059700D01*
X377700Y-1060767D01*
X378100Y-1061567D01*
X378700Y-1062233D01*
X379500Y-1062500D01*
X380300Y-1062233D01*
X380900Y-1061567D01*
X381300Y-1060767D01*
X381600Y-1059700D01*
X381700Y-1058500D01*
X381600Y-1057300D01*
X381300Y-1056233D01*
X380900Y-1055433D01*
X380300Y-1054767D01*
X379500Y-1054500D01*
G01X385600Y-1055833D02*
X386200Y-1055033D01*
X386900Y-1054633D01*
X387700Y-1054500D01*
X388700Y-1054767D01*
X389400Y-1055433D01*
X389600Y-1056233D01*
X389500Y-1057034D01*
X389100Y-1057700D01*
X387100Y-1059033D01*
X386200Y-1059967D01*
X385600Y-1061300D01*
X385400Y-1062500D01*
X389600D01*
G01X393600Y-1055833D02*
X394200Y-1055033D01*
X394900Y-1054633D01*
X395700Y-1054500D01*
X396700Y-1054767D01*
X397400Y-1055433D01*
X397600Y-1056233D01*
X397500Y-1057034D01*
X397100Y-1057700D01*
X395100Y-1059033D01*
X394200Y-1059967D01*
X393600Y-1061300D01*
X393400Y-1062500D01*
X397600D01*
G01X401700Y-1062767D02*
X405300Y-1054500D01*
G01X411500Y-1062500D02*
Y-1054500D01*
X410300Y-1056100D01*
G01Y-1062500D02*
X412700D01*
G01X417600Y-1055833D02*
X418200Y-1055033D01*
X418900Y-1054633D01*
X419700Y-1054500D01*
X420700Y-1054767D01*
X421400Y-1055433D01*
X421600Y-1056233D01*
X421500Y-1057034D01*
X421100Y-1057700D01*
X419100Y-1059033D01*
X418200Y-1059967D01*
X417600Y-1061300D01*
X417400Y-1062500D01*
X421600D01*
G01X425700Y-1062767D02*
X429300Y-1054500D01*
G01X435500Y-1062500D02*
Y-1054500D01*
X434300Y-1056100D01*
G01Y-1062500D02*
X436700D01*
G01X441300Y-1060900D02*
X441900Y-1061833D01*
X442700Y-1062367D01*
X443600Y-1062500D01*
X444400Y-1062367D01*
X445200Y-1061700D01*
X445700Y-1060900D01*
X445800Y-1060100D01*
X445600Y-1059167D01*
X444900Y-1058500D01*
X444200Y-1058233D01*
X443300D01*
G01X444200D02*
X444800Y-1057833D01*
X445300Y-1057167D01*
X445500Y-1056367D01*
X445300Y-1055567D01*
X444800Y-1054900D01*
X443900Y-1054500D01*
X443000Y-1054633D01*
X442100Y-1055167D01*
G01X369300Y-1040000D02*
Y-1032000D01*
X371300D01*
X372100Y-1032400D01*
X372700Y-1032933D01*
X373200Y-1033733D01*
X373600Y-1034667D01*
X373700Y-1036000D01*
X373600Y-1037333D01*
X373200Y-1038267D01*
X372700Y-1039067D01*
X372100Y-1039600D01*
X371300Y-1040000D01*
X369300D01*
G01X377000D02*
X379500Y-1032000D01*
X382000Y-1040000D01*
G01X381100Y-1037200D02*
X377900D01*
G01X385600Y-1040000D02*
Y-1032000D01*
X389400D01*
G01X388000Y-1035867D02*
X385600D01*
G01X395500Y-1032000D02*
X394700Y-1032267D01*
X394100Y-1032933D01*
X393700Y-1033733D01*
X393400Y-1034800D01*
X393300Y-1036000D01*
X393400Y-1037200D01*
X393700Y-1038267D01*
X394100Y-1039067D01*
X394700Y-1039733D01*
X395500Y-1040000D01*
X396300Y-1039733D01*
X396900Y-1039067D01*
X397300Y-1038267D01*
X397600Y-1037200D01*
X397700Y-1036000D01*
X397600Y-1034800D01*
X397300Y-1033733D01*
X396900Y-1032933D01*
X396300Y-1032267D01*
X395500Y-1032000D01*
G01X403500D02*
Y-1040000D01*
G01X401200Y-1032000D02*
X405800D01*
G01X409500Y-1040000D02*
Y-1032000D01*
X411900D01*
X412700Y-1032400D01*
X413300Y-1033333D01*
X413500Y-1034400D01*
X413300Y-1035467D01*
X412800Y-1036267D01*
X411900Y-1036667D01*
X409500D01*
G01X420300Y-1035733D02*
X420700Y-1035333D01*
X421000Y-1034667D01*
X421200Y-1033733D01*
X421000Y-1032933D01*
X420600Y-1032400D01*
X419900Y-1032000D01*
X417200D01*
Y-1040000D01*
X420500D01*
X421200Y-1039467D01*
X421600Y-1038667D01*
X421800Y-1037733D01*
X421600Y-1036800D01*
X421000Y-1036000D01*
X420300Y-1035733D01*
X417200D01*
G01X427500Y-1040000D02*
Y-1032000D01*
X426300Y-1033600D01*
G01Y-1040000D02*
X428700D01*
G01X433000D02*
X435500Y-1032000D01*
X438000Y-1040000D01*
G01X437100Y-1037200D02*
X433900D01*
G01X441600Y-1040000D02*
Y-1032000D01*
X445400D01*
G01X444000Y-1035867D02*
X441600D01*
G01X451500Y-1032000D02*
X450700Y-1032267D01*
X450100Y-1032933D01*
X449700Y-1033733D01*
X449400Y-1034800D01*
X449300Y-1036000D01*
X449400Y-1037200D01*
X449700Y-1038267D01*
X450100Y-1039067D01*
X450700Y-1039733D01*
X451500Y-1040000D01*
X452300Y-1039733D01*
X452900Y-1039067D01*
X453300Y-1038267D01*
X453600Y-1037200D01*
X453700Y-1036000D01*
X453600Y-1034800D01*
X453300Y-1033733D01*
X452900Y-1032933D01*
X452300Y-1032267D01*
X451500Y-1032000D01*
G01X389600Y-1012500D02*
Y-1004500D01*
X393400D01*
G01X392000Y-1008367D02*
X389600D01*
G01X399500Y-1004500D02*
X398700Y-1004767D01*
X398100Y-1005433D01*
X397700Y-1006233D01*
X397400Y-1007300D01*
X397300Y-1008500D01*
X397400Y-1009700D01*
X397700Y-1010767D01*
X398100Y-1011567D01*
X398700Y-1012233D01*
X399500Y-1012500D01*
X400300Y-1012233D01*
X400900Y-1011567D01*
X401300Y-1010767D01*
X401600Y-1009700D01*
X401700Y-1008500D01*
X401600Y-1007300D01*
X401300Y-1006233D01*
X400900Y-1005433D01*
X400300Y-1004767D01*
X399500Y-1004500D01*
G01X407500D02*
Y-1012500D01*
G01X405200Y-1004500D02*
X409800D01*
G01X412500Y-1015167D02*
X418500D01*
G01X421500Y-1012500D02*
Y-1004500D01*
X423900D01*
X424700Y-1004900D01*
X425300Y-1005833D01*
X425500Y-1006900D01*
X425300Y-1007967D01*
X424800Y-1008767D01*
X423900Y-1009167D01*
X421500D01*
G01X429300Y-1012500D02*
Y-1004500D01*
X431300D01*
X432100Y-1004900D01*
X432700Y-1005433D01*
X433200Y-1006233D01*
X433600Y-1007167D01*
X433700Y-1008500D01*
X433600Y-1009833D01*
X433200Y-1010767D01*
X432700Y-1011567D01*
X432100Y-1012100D01*
X431300Y-1012500D01*
X429300D01*
G01X440300Y-1008233D02*
X440700Y-1007833D01*
X441000Y-1007167D01*
X441200Y-1006233D01*
X441000Y-1005433D01*
X440600Y-1004900D01*
X439900Y-1004500D01*
X437200D01*
Y-1012500D01*
X440500D01*
X441200Y-1011967D01*
X441600Y-1011167D01*
X441800Y-1010233D01*
X441600Y-1009300D01*
X441000Y-1008500D01*
X440300Y-1008233D01*
X437200D01*
G01X444500Y-1015167D02*
X450500D01*
G01X456300Y-1008233D02*
X456700Y-1007833D01*
X457000Y-1007167D01*
X457200Y-1006233D01*
X457000Y-1005433D01*
X456600Y-1004900D01*
X455900Y-1004500D01*
X453200D01*
Y-1012500D01*
X456500D01*
X457200Y-1011967D01*
X457600Y-1011167D01*
X457800Y-1010233D01*
X457600Y-1009300D01*
X457000Y-1008500D01*
X456300Y-1008233D01*
X453200D01*
G01X461300Y-1012500D02*
Y-1004500D01*
X463300D01*
X464100Y-1004900D01*
X464700Y-1005433D01*
X465200Y-1006233D01*
X465600Y-1007167D01*
X465700Y-1008500D01*
X465600Y-1009833D01*
X465200Y-1010767D01*
X464700Y-1011567D01*
X464100Y-1012100D01*
X463300Y-1012500D01*
X461300D01*
G01X468500Y-1015167D02*
X474500D01*
G01X480100Y-1008500D02*
X482100D01*
Y-1010900D01*
X481500Y-1011700D01*
X480800Y-1012233D01*
X479800Y-1012500D01*
X478800Y-1012233D01*
X478100Y-1011700D01*
X477500Y-1010900D01*
X477100Y-1009967D01*
X476900Y-1008900D01*
Y-1007967D01*
X477100Y-1007167D01*
X477500Y-1006233D01*
X478100Y-1005433D01*
X478700Y-1004900D01*
X479500Y-1004500D01*
X480200D01*
X481000Y-1004767D01*
X481600Y-1005300D01*
G01X485500Y-1012500D02*
Y-1004500D01*
X487900D01*
X488700Y-1004900D01*
X489300Y-1005833D01*
X489500Y-1006900D01*
X489300Y-1007967D01*
X488800Y-1008767D01*
X487900Y-1009167D01*
X485500D01*
G01X493300Y-1004500D02*
Y-1010233D01*
X493700Y-1011434D01*
X494500Y-1012233D01*
X495500Y-1012500D01*
X496500Y-1012233D01*
X497300Y-1011434D01*
X497700Y-1010233D01*
Y-1004500D01*
G01X458000Y-1065500D02*
Y-1057500D01*
X456800Y-1059100D01*
G01Y-1065500D02*
X459200D01*
G01X464100Y-1062167D02*
X464800Y-1061233D01*
X465400Y-1060700D01*
X466200Y-1060433D01*
X466900Y-1060700D01*
X467400Y-1061233D01*
X467800Y-1062033D01*
X467900Y-1062967D01*
X467800Y-1063767D01*
X467400Y-1064567D01*
X466800Y-1065233D01*
X466100Y-1065500D01*
X465300Y-1065233D01*
X464600Y-1064434D01*
X464200Y-1063233D01*
X464100Y-1061900D01*
X464300Y-1060167D01*
X464600Y-1059233D01*
X465100Y-1058300D01*
X465800Y-1057633D01*
X466500Y-1057500D01*
X467200Y-1057767D01*
X467700Y-1058433D01*
G01X474000Y-1065767D02*
X473800Y-1065633D01*
Y-1065367D01*
X474000Y-1065233D01*
X474200Y-1065367D01*
Y-1065633D01*
X474000Y-1065767D01*
G01X480100Y-1062167D02*
X480800Y-1061233D01*
X481400Y-1060700D01*
X482200Y-1060433D01*
X482900Y-1060700D01*
X483400Y-1061233D01*
X483800Y-1062033D01*
X483900Y-1062967D01*
X483800Y-1063767D01*
X483400Y-1064567D01*
X482800Y-1065233D01*
X482100Y-1065500D01*
X481300Y-1065233D01*
X480600Y-1064434D01*
X480200Y-1063233D01*
X480100Y-1061900D01*
X480300Y-1060167D01*
X480600Y-1059233D01*
X481100Y-1058300D01*
X481800Y-1057633D01*
X482500Y-1057500D01*
X483200Y-1057767D01*
X483700Y-1058433D01*
G01X503000Y-1065500D02*
Y-1057500D01*
X501800Y-1059100D01*
G01Y-1065500D02*
X504200D01*
G01X510800D02*
X511000Y-1063767D01*
X511300Y-1062300D01*
X511700Y-1060967D01*
X512200Y-1059500D01*
X513000Y-1057500D01*
X509000D01*
G01X519000Y-1065767D02*
X518800Y-1065633D01*
Y-1065367D01*
X519000Y-1065233D01*
X519200Y-1065367D01*
Y-1065633D01*
X519000Y-1065767D01*
G01X525100Y-1058833D02*
X525700Y-1058033D01*
X526400Y-1057633D01*
X527200Y-1057500D01*
X528200Y-1057767D01*
X528900Y-1058433D01*
X529100Y-1059233D01*
X529000Y-1060034D01*
X528600Y-1060700D01*
X526600Y-1062033D01*
X525700Y-1062967D01*
X525100Y-1064300D01*
X524900Y-1065500D01*
X529100D01*
G01X523100Y-1040500D02*
Y-1032500D01*
X526900D01*
G01X525500Y-1036367D02*
X523100D01*
G54D17*
X802087Y145984D03*
X792087D03*
X802087Y135984D03*
X792087D03*
X802087Y180984D03*
X792087D03*
X802087Y170984D03*
X792087D03*
X802087Y200984D03*
X792087D03*
X802087Y230984D03*
X792087D03*
X802087Y220984D03*
X792087D03*
X802087Y265984D03*
X792087D03*
X802087Y255984D03*
X792087D03*
X822087Y145984D03*
X812087D03*
X822087Y135984D03*
X812087D03*
X822087Y180984D03*
X812087D03*
X822087Y170984D03*
X812087D03*
X822087Y230984D03*
X812087D03*
X822087Y220984D03*
X812087D03*
X822087Y265984D03*
X812087D03*
X822087Y255984D03*
X812087D03*
X920197Y145984D03*
X910197D03*
X920197Y135984D03*
X910197D03*
X920197Y180984D03*
X910197D03*
X920197Y170984D03*
X910197D03*
X920197Y200984D03*
X910197D03*
X920197Y230984D03*
X910197D03*
X920197Y220984D03*
X910197D03*
X920197Y265984D03*
X910197D03*
X920197Y255984D03*
X910197D03*
X940197Y145984D03*
X930197D03*
X940197Y135984D03*
X930197D03*
X940197Y180984D03*
X930197D03*
X940197Y170984D03*
X930197D03*
X940197Y230984D03*
X930197D03*
X940197Y220984D03*
X930197D03*
X940197Y265984D03*
X930197D03*
X940197Y255984D03*
X930197D03*
G54D27*
G01X187600Y106500D02*
X180600Y99500D01*
X158624D01*
X158573Y99506D01*
X158530Y99540D01*
X156785Y101285D01*
G01X210925Y115575D02*
X191675D01*
X178100Y102000D01*
X176785D01*
G01X862600Y29500D02*
X853764Y20664D01*
X417458D01*
X356985Y81137D01*
X310326D01*
X285388Y106075D01*
X211425D01*
G01X317000Y58000D02*
X282012Y23012D01*
X279646D01*
G01X321500Y66500D02*
X316001D01*
X314500Y64999D01*
Y59000D01*
X285500Y30000D01*
X282347D01*
X274646Y22299D01*
Y18012D01*
G01X325100Y64000D02*
Y62753D01*
X279646Y17299D01*
Y13012D01*
G01X332500Y63300D02*
Y62900D01*
X293500Y23900D01*
Y19043D01*
X290500Y16043D01*
X288390D01*
X280359Y8012D01*
X274646D01*
G01X289646Y23012D02*
Y24032D01*
X327700Y62086D01*
Y63800D01*
X330501Y66601D01*
X353063D01*
X410709Y8955D01*
X1413056D01*
X1430171Y26070D01*
X1501629D01*
X1515129Y12570D01*
X1624003D01*
X1688003Y76570D01*
X1692000D01*
G01X317000Y74475D02*
Y74001D01*
X322090Y68911D01*
X354020D01*
X411649Y11282D01*
X1381384D01*
X1398482Y28380D01*
X1502586D01*
X1516086Y14880D01*
X1622914D01*
X1686914Y78880D01*
X1723517D01*
X1735637Y91000D01*
X1766500D01*
X1771000Y95500D01*
Y110541D01*
X1767525Y114016D01*
G01X321500Y74475D02*
X322734D01*
X325988Y71221D01*
X354977D01*
X412606Y13592D01*
X1380427D01*
X1397525Y30690D01*
X1503543D01*
X1517043Y17190D01*
X1621957D01*
X1685957Y81190D01*
X1722560D01*
X1734680Y93310D01*
X1742222D01*
X1742957Y94045D01*
Y103765D01*
X1743692Y104500D01*
X1744733D01*
X1745468Y103765D01*
Y94045D01*
X1746203Y93310D01*
X1747244D01*
X1747979Y94045D01*
Y103765D01*
X1748714Y104500D01*
X1749755D01*
X1750490Y103765D01*
Y94045D01*
X1751225Y93310D01*
X1752266D01*
X1753001Y94045D01*
Y103765D01*
X1753736Y104500D01*
X1754777D01*
X1755512Y103765D01*
Y94045D01*
X1756247Y93310D01*
X1765411D01*
X1767425Y95324D01*
Y107000D01*
G01X317000Y64500D02*
Y58000D01*
G01X1499228Y74500D02*
X1491000D01*
X1486807Y70307D01*
Y49307D01*
X1470500Y33000D01*
X1396568D01*
X1379470Y15902D01*
X413563D01*
X354989Y74476D01*
X330500D01*
G01X1503728Y74477D02*
Y74604D01*
X1500332Y78000D01*
X1484400D01*
X1470405Y91995D01*
X1443297D01*
X1430530Y79228D01*
Y39263D01*
X1426757Y35490D01*
X1395791D01*
X1378513Y18212D01*
X415784D01*
X355939Y78061D01*
X329481D01*
X326000Y74580D01*
Y74476D01*
G01X396216Y46875D02*
X420090Y23001D01*
X852741D01*
X863332Y33592D01*
X871777D01*
X877879Y27490D01*
X1374723D01*
X1421290Y74057D01*
Y83056D01*
X1439469Y101235D01*
X1507188D01*
X1521249Y115296D01*
X1578596D01*
X1602644Y139344D01*
Y147261D01*
X1604308Y148925D01*
X1618100D01*
G01X662100Y304500D02*
X654500Y312100D01*
Y364190D01*
X628000Y390690D01*
X542937D01*
X514500Y362253D01*
X507000D01*
X502000Y367253D01*
Y378200D01*
X524058Y400258D01*
X1367182D01*
X1478940Y288500D01*
X1585999D01*
X1664000Y210499D01*
Y202500D01*
G01X1622100Y155931D02*
X1612326Y165705D01*
Y197328D01*
X1570668Y238986D01*
X1479279D01*
X1408383Y309882D01*
X1324801D01*
X1292183Y342500D01*
X1158900D01*
X1156500Y340100D01*
X1106400D01*
X1099000Y347500D01*
X1032900D01*
X1007300Y321900D01*
X975800D01*
X943800Y353900D01*
X905500D01*
X882500Y376900D01*
X877900D01*
X875500Y374500D01*
Y368768D01*
X872400Y365668D01*
Y360334D01*
X867566Y355500D01*
X813200D01*
X779409Y321709D01*
X709107D01*
X703681Y316283D01*
X688923D01*
X684300Y311660D01*
Y305883D01*
X670317Y291900D01*
X643546D01*
X622946Y312500D01*
X598600D01*
X594300Y308200D01*
Y297400D01*
X602200Y289500D01*
Y263000D01*
X605700Y259500D01*
G01X612684Y297000D02*
X628645D01*
X657259Y268386D01*
Y263000D01*
G01X616684Y294500D02*
X627878D01*
X654949Y267429D01*
Y263849D01*
X654100Y263000D01*
G01X683592Y259908D02*
X679776D01*
X678100Y261584D01*
Y270000D01*
X676100Y272000D01*
X656912D01*
X629602Y299310D01*
X619000D01*
X610455Y307855D01*
X601240D01*
X599820Y306435D01*
Y300259D01*
X602928Y297151D01*
Y293969D01*
G01X600875Y295937D02*
X597510Y299302D01*
Y307392D01*
X600283Y310165D01*
X611412D01*
X619957Y301620D01*
X630559D01*
X655779Y276400D01*
X680300D01*
X683994Y272706D01*
Y264712D01*
X688945Y259761D01*
G01X670184Y288500D02*
X686610Y304926D01*
Y310703D01*
X689880Y313973D01*
X704638D01*
X709895Y319230D01*
X790829D01*
X824109Y352510D01*
X867843D01*
X874887Y359554D01*
Y364888D01*
X878175Y368176D01*
Y374100D01*
G01X662184Y280500D02*
X665456D01*
X688920Y303964D01*
Y309746D01*
X690837Y311663D01*
X720663D01*
X725730Y316730D01*
X791596D01*
X825066Y350200D01*
X868800D01*
X878175Y359575D01*
Y364709D01*
G01X658925Y320000D02*
X661425Y317500D01*
X665000D01*
X666500Y319000D01*
X702799D01*
X707900Y324101D01*
Y361901D01*
X734396Y388397D01*
X882603D01*
X903000Y368000D01*
X918500D01*
X932652Y382152D01*
X992047D01*
X1021509Y352690D01*
X1077889D01*
X1092089Y366890D01*
X1117010D01*
X1119900Y364000D01*
X1158000D01*
X1168690Y374690D01*
X1218812D01*
X1230519Y386397D01*
X1361437D01*
X1487787Y260047D01*
X1582326D01*
X1640165Y202208D01*
Y186335D01*
X1642000Y184500D01*
G01X691759Y309000D02*
X721267D01*
X726687Y314420D01*
X792553D01*
X825949Y347816D01*
X871416D01*
X885100Y361500D01*
G01X681498Y565042D02*
X976382D01*
X976892Y565552D01*
Y574532D01*
X976382Y575042D01*
X681498D01*
G01X710900Y324100D02*
Y360400D01*
X735500Y385000D01*
X813500D01*
X821000Y377500D01*
X869500D01*
X874500Y382500D01*
X883765D01*
X885265Y381000D01*
G01X719433Y328087D02*
X723354Y324166D01*
X769533D01*
X812367Y367000D01*
X869200D01*
X872500Y370300D01*
Y375500D01*
X876500Y379500D01*
X883300D01*
X906300Y356500D01*
X944600D01*
X975900Y325200D01*
X1002140D01*
X1023492Y346552D01*
Y346593D01*
G01X1026270Y303729D02*
X1015809Y314190D01*
X973043D01*
X943233Y344000D01*
X903917D01*
X889417Y358500D01*
X885367D01*
X872373Y345506D01*
X826906D01*
X786400Y305000D01*
X728425D01*
X722925Y299500D01*
G01X717401Y329996D02*
X713600Y333797D01*
Y358100D01*
X738000Y382500D01*
X810000D01*
X820300Y372200D01*
X825900D01*
G01X770700Y206900D02*
X772300Y205300D01*
Y199800D01*
X775900Y196200D01*
X796100D01*
X800884Y200984D01*
X802087D01*
G01X776000Y206600D02*
X778200D01*
X783816Y200984D01*
X792087D01*
G01X872533Y29432D02*
X876823Y25142D01*
X1375642D01*
X1423600Y73100D01*
Y82099D01*
X1440426Y98925D01*
X1527100D01*
G01X1705100Y140500D02*
Y135600D01*
X1699220Y129720D01*
Y127086D01*
X1692100Y119966D01*
Y103668D01*
X1617742Y29310D01*
X1587290D01*
X1555100Y61500D01*
X1527100D01*
X1494295Y94305D01*
X1442340D01*
X1428220Y80185D01*
Y40220D01*
X1425800Y37800D01*
X1394834D01*
X1377556Y20522D01*
X874578D01*
X867100Y28000D01*
G01X1707100Y142500D02*
X1703999D01*
X1701299Y139800D01*
Y135066D01*
X1696910Y130677D01*
Y128043D01*
X1689790Y120923D01*
Y104625D01*
X1616785Y31620D01*
X1588247D01*
X1556057Y63810D01*
X1528057D01*
X1495252Y96615D01*
X1441383D01*
X1425910Y81142D01*
Y72143D01*
X1376599Y22832D01*
X875768D01*
X867100Y31500D01*
G01X1070525Y243000D02*
X1064114Y249411D01*
X1048061D01*
X1035333Y262139D01*
Y279139D01*
X1036607Y280413D01*
Y284993D01*
X1013600Y308000D01*
X975001D01*
X941311Y341690D01*
X901490D01*
X887500Y355680D01*
G01X878175Y374100D02*
X882000D01*
X904583Y351517D01*
X942483D01*
X974500Y319500D01*
X1017033D01*
X1031566Y304967D01*
Y301661D01*
X1049390Y283837D01*
X1061548D01*
X1064101Y286390D01*
X1076310D01*
X1080300Y282400D01*
Y271300D01*
X1088100Y263500D01*
X1092100D01*
G01X1101500Y271500D02*
X1095000Y265000D01*
Y262912D01*
X1093088Y261000D01*
X1055000D01*
X1049800Y266200D01*
Y280160D01*
X1029256Y300704D01*
Y304010D01*
X1016766Y316500D01*
X974000D01*
X941500Y349000D01*
X937021D01*
X936257Y348236D01*
Y347264D01*
X935493Y346500D01*
X934411D01*
X933647Y347264D01*
Y348236D01*
X932883Y349000D01*
X931801D01*
X931037Y348236D01*
Y347264D01*
X930273Y346500D01*
X929191D01*
X928427Y347264D01*
Y348236D01*
X927663Y349000D01*
X926581D01*
X925817Y348236D01*
Y347264D01*
X925053Y346500D01*
X923971D01*
X923207Y347264D01*
Y348236D01*
X922443Y349000D01*
X921361D01*
X920597Y348236D01*
Y347264D01*
X919833Y346500D01*
X918751D01*
X917987Y347264D01*
Y348236D01*
X917223Y349000D01*
X916141D01*
X915377Y348236D01*
Y347264D01*
X914613Y346500D01*
X913531D01*
X912767Y347264D01*
Y348236D01*
X912003Y349000D01*
X902184D01*
X886475Y364709D01*
X878175D01*
G01X954200Y200200D02*
X947400Y207000D01*
X922900D01*
X920197Y204297D01*
Y200984D01*
G01X954600Y207200D02*
X951700Y210100D01*
X913300D01*
X910197Y206997D01*
Y200984D01*
G01X906900Y372200D02*
X919162Y384462D01*
X993004D01*
X1021414Y356052D01*
Y355979D01*
G01X1017300Y385600D02*
X1006400Y396500D01*
X894500D01*
G01X1017300Y322500D02*
X1033876Y305924D01*
Y302618D01*
X1050347Y286147D01*
X1060591D01*
X1063144Y288700D01*
X1078024D01*
X1088079Y278645D01*
Y274980D01*
G01X1772600Y177300D02*
X1775500Y174400D01*
Y157000D01*
X1770810Y152310D01*
X1730190D01*
X1721000Y161500D01*
X1711500D01*
X1705000Y168000D01*
X1696301D01*
X1686173Y178128D01*
X1671371D01*
X1667309Y182190D01*
X1656690D01*
X1652628Y178128D01*
X1640371D01*
X1633500Y184999D01*
Y202000D01*
X1580344Y255156D01*
X1486144D01*
X1414783Y326517D01*
X1331140D01*
X1287587Y370070D01*
X1202571D01*
X1194771Y362270D01*
X1163169D01*
X1160089Y359190D01*
X1116890D01*
X1115700Y358000D01*
X1086499D01*
X1078499Y350000D01*
X1026940D01*
X1023533Y346593D01*
X1023492D01*
G01X1100100Y247500D02*
X1107300Y240300D01*
X1147100D01*
X1151455Y244655D01*
Y275055D01*
X1160945Y284545D01*
Y293200D01*
X1158749Y295396D01*
X1156509D01*
G01X1129800Y265400D02*
Y270300D01*
X1126200Y273900D01*
X1089159D01*
X1088079Y274980D01*
G01X1080600Y294000D02*
X1115200Y328600D01*
X1162500D01*
X1166200Y324900D01*
Y317000D01*
X1169400Y313800D01*
Y279899D01*
X1165700Y276199D01*
Y254566D01*
X1163268Y252134D01*
X1160990D01*
G01X1163266Y255311D02*
Y277966D01*
X1166917Y281617D01*
Y312984D01*
X1163344Y316557D01*
Y324244D01*
X1161471Y326117D01*
X1115984D01*
X1081557Y291690D01*
X1073888D01*
X1073339Y292239D01*
G01X1153500Y342500D02*
X1151310Y344690D01*
X1145957D01*
X1143677Y342410D01*
X1107690D01*
X1094500Y355600D01*
G01Y360500D02*
X1114582D01*
X1115582Y361500D01*
X1158767D01*
X1169647Y372380D01*
X1219769D01*
X1231476Y384087D01*
X1360480D01*
X1487101Y257466D01*
X1581640D01*
X1636000Y203106D01*
Y186000D01*
X1640000Y182000D01*
X1642500D01*
X1645000Y184500D01*
G01X1145600Y257500D02*
X1141700Y261400D01*
Y280500D01*
X1137100Y285100D01*
X1115700D01*
X1111800Y289000D01*
X1108100D01*
G01X1105025D02*
Y286675D01*
X1111445Y280255D01*
X1125675D01*
X1128120Y282700D01*
X1135901D01*
X1139200Y279401D01*
Y259790D01*
X1143990Y255000D01*
X1149600D01*
G01X1178900Y359620D02*
X1163820D01*
X1160500Y356300D01*
X1123400D01*
G01X1141500Y347500D02*
X1143500Y349500D01*
X1153034D01*
X1155034Y347500D01*
X1293717D01*
X1326533Y314684D01*
X1410115D01*
X1481193Y243606D01*
X1573026D01*
X1617732Y198900D01*
Y168395D01*
X1624527Y161600D01*
X1667100D01*
X1678700Y150000D01*
X1765525D01*
X1773000Y142525D01*
G01X1138500Y347500D02*
X1140810Y345190D01*
X1143190D01*
X1145000Y347000D01*
X1152267D01*
X1154267Y345000D01*
X1292950D01*
X1325758Y312192D01*
X1409340D01*
X1480236Y241296D01*
X1571625D01*
X1615063Y197858D01*
Y167797D01*
X1623660Y159200D01*
X1639779D01*
X1642243Y156736D01*
Y152764D01*
X1643007Y152000D01*
X1644089D01*
X1644853Y152764D01*
Y156736D01*
X1645617Y157500D01*
X1646699D01*
X1647463Y156736D01*
Y152764D01*
X1648227Y152000D01*
X1649309D01*
X1650073Y152764D01*
Y156736D01*
X1650837Y157500D01*
X1651919D01*
X1652683Y156736D01*
Y152764D01*
X1653447Y152000D01*
X1654529D01*
X1655293Y152764D01*
Y156736D01*
X1656057Y157500D01*
X1657139D01*
X1657903Y156736D01*
Y152764D01*
X1658667Y152000D01*
X1659749D01*
X1660513Y152764D01*
Y156736D01*
X1661277Y157500D01*
X1662359D01*
X1663123Y156736D01*
Y152764D01*
X1663887Y152000D01*
X1664969D01*
X1665733Y152764D01*
Y156736D01*
X1666497Y157500D01*
X1667579D01*
X1668343Y156736D01*
Y148424D01*
X1673957Y142810D01*
X1696543D01*
X1701043Y147310D01*
X1711715D01*
X1714100Y144925D01*
G01X1163000Y352500D02*
Y355000D01*
X1165310Y357310D01*
X1193310D01*
X1203700Y367700D01*
X1286689D01*
X1330182Y324207D01*
X1413826D01*
X1485187Y252846D01*
X1578655D01*
X1629000Y202501D01*
Y181100D01*
X1636600Y173500D01*
G01X1624000Y189000D02*
Y200501D01*
X1576275Y248226D01*
X1483272D01*
X1411911Y319587D01*
X1328268D01*
X1295355Y352500D01*
X1166000D01*
G01X1658000Y179500D02*
Y176500D01*
X1657318Y175818D01*
X1646008D01*
X1640500Y170310D01*
X1621690D01*
X1620042Y171958D01*
Y199857D01*
X1573983Y245916D01*
X1482315D01*
X1410954Y317277D01*
X1327310D01*
X1294587Y350000D01*
X1179500D01*
G01Y355000D02*
X1195232D01*
X1205622Y365390D01*
X1285732D01*
X1329225Y321897D01*
X1412869D01*
X1484230Y250536D01*
X1577464D01*
X1626500Y201500D01*
Y177500D01*
X1629000Y175000D01*
G01X1695500Y76500D02*
X1693260Y74260D01*
X1688960D01*
X1624960Y10260D01*
X1514172D01*
X1501420Y23012D01*
X1480197D01*
G01X1719075Y107016D02*
X1698715D01*
X1618699Y27000D01*
X1522335D01*
X1512235Y37100D01*
Y72632D01*
X1501367Y83500D01*
X1494728D01*
G01X1719075Y112000D02*
X1722000Y109075D01*
Y106000D01*
X1720000Y104000D01*
X1713967D01*
X1713203Y103236D01*
Y96764D01*
X1712439Y96000D01*
X1711357D01*
X1710593Y96764D01*
Y103236D01*
X1709829Y104000D01*
X1708747D01*
X1707983Y103236D01*
Y96764D01*
X1707219Y96000D01*
X1706137D01*
X1705373Y96764D01*
Y103236D01*
X1704609Y104000D01*
X1698966D01*
X1619466Y24500D01*
X1521000D01*
X1509925Y35575D01*
Y71675D01*
X1501100Y80500D01*
X1490000D01*
G01X1738000Y124500D02*
Y99897D01*
X1721603Y83500D01*
X1685000D01*
X1621000Y19500D01*
X1518000D01*
X1501566Y35934D01*
Y66734D01*
X1499228Y69072D01*
Y74500D01*
G01X1503728Y74477D02*
X1507359Y70846D01*
Y33642D01*
X1519001Y22000D01*
X1620233D01*
X1684043Y85810D01*
X1720309D01*
X1730500Y96001D01*
Y122500D01*
X1736500Y128500D01*
X1748500D01*
X1760000Y117000D01*
X1766000D01*
X1769500Y120500D01*
Y125500D01*
X1773500Y129500D01*
G01X1567500Y67000D02*
Y74425D01*
X1530425Y111500D01*
X1524600D01*
G01X1626925Y156000D02*
X1631323Y151602D01*
Y115140D01*
G01X1701000Y159000D02*
X1697500Y155500D01*
X1684000D01*
X1674000Y165500D01*
X1628000D01*
X1626000Y163500D01*
G01X1701000Y164500D02*
X1699000Y162500D01*
X1697000D01*
X1691500Y168000D01*
X1626500D01*
X1626000Y167500D01*
G01X1721600Y194760D02*
X1702241D01*
X1692001Y205000D01*
X1677499D01*
X1668999Y196500D01*
X1664000D01*
X1661500Y199000D01*
G01X1667600Y198500D02*
X1676600Y207500D01*
X1692768D01*
X1701768Y198500D01*
X1721600D01*
G01X1764100Y119500D02*
X1761100D01*
X1749100Y131500D01*
X1720400D01*
X1707900Y119000D01*
X1696600D01*
G01X1773000Y158000D02*
X1769116Y161884D01*
X1723883D01*
X1720267Y165500D01*
X1713500D01*
X1710964Y168036D01*
X1702600Y171500D01*
G01D02*
X1694918Y174682D01*
X1685975Y183625D01*
Y186500D01*
G01X1715525Y168500D02*
X1757500D01*
X1768000Y179000D01*
X1771000D01*
X1774000Y182000D01*
X1794600D01*
X1800100Y187500D01*
G01X1809600Y195000D02*
X1746499D01*
X1728475Y176976D01*
Y175000D01*
G01X1721500Y205000D02*
X1725500Y201000D01*
X1807367D01*
X1817500Y190867D01*
Y188000D01*
G01X1811500Y186000D02*
X1808000Y189500D01*
X1778000D01*
G54D18*
X825900Y372200D03*
X906900D03*
G54D19*
X1848583Y99212D03*
X1848582Y481693D03*
M02*
